FILE_TYPE = MACRO_DRAWING;
SET COLOR_WIRE YELLOW;
SET COLOR_PROP ORANGE;
SET COLOR_DOT WHITE;
SET COLOR_ARC YELLOW;
SET COLOR_BODY GREEN;
SET COLOR_NOTE PURPLE;
SET PROP_DISPLAY VALUE;
SET PAGE_NUMBER P348;
FORCEADD OFFPAGE..5
(-15975 4475);
FORCEPROP 2 LAST $XR1 80 
J 0
(-16350 4475);
DISPLAY 0.638298 (-16350 4475);
PAINT MONO (-16350 4475);
FORCEPROP 2 LAST $XR0 150 
J 0
(-16260 4475);
DISPLAY 0.638298 (-16260 4475);
PAINT MONO (-16260 4475);
FORCEPROP 2 LAST CDS_LIB standard
J 0
(-15975 4475);
DISPLAY INVISIBLE (-15975 4475);
FORCEPROP 1 LAST OFFPAGE TRUE
J 0
(-15650 4350);
DISPLAY 0.872340 (-15650 4350);
PAINT GREEN (-15650 4350);
DISPLAY INVISIBLE (-15650 4350);
FORCEPROP 1 LAST COMMENT_BODY TRUE
J 0
(-15875 4400);
DISPLAY 0.872340 (-15875 4400);
PAINT PEACH (-15875 4400);
DISPLAY INVISIBLE (-15875 4400);
FORCEPROP 2 LAST PATH I1
J 0
(-15925 4550);
DISPLAY 0.680851 (-15925 4550);
DISPLAY INVISIBLE (-15925 4550);
FORCEADD OFFPAGE..1
(-16225 6325);
FORCEPROP 2 LAST $XR0 254 
J 0
(-16477 6325);
DISPLAY 0.638298 (-16477 6325);
PAINT MONO (-16477 6325);
FORCEPROP 2 LAST CDS_LIB standard
J 0
(-16225 6325);
PAINT MONO (-16225 6325);
DISPLAY INVISIBLE (-16225 6325);
FORCEPROP 1 LAST OFFPAGE TRUE
J 0
(-15900 6200);
DISPLAY 0.872340 (-15900 6200);
PAINT GREEN (-15900 6200);
DISPLAY INVISIBLE (-15900 6200);
FORCEPROP 1 LAST COMMENT_BODY TRUE
J 0
(-16100 6225);
DISPLAY 0.872340 (-16100 6225);
PAINT PEACH (-16100 6225);
DISPLAY INVISIBLE (-16100 6225);
FORCEPROP 2 LAST PATH I10
J 0
(-16175 6400);
DISPLAY 0.680851 (-16175 6400);
DISPLAY INVISIBLE (-16175 6400);
FORCEADD Q_RES..1
(-14925 8425);
FORCEPROP 1 LAST LOCATION R2422
J 0
(-15150 8425);
DISPLAY 0.638298 (-15150 8425);
FORCEPROP 0 LAST $SEC 1
J 0
(-15150 8475);
DISPLAY 0.680851 (-15150 8475);
PAINT MONO (-15150 8475);
DISPLAY INVISIBLE (-15150 8475);
FORCEPROP 0 LAST CDS_SEC 1
J 0
(-15150 8475);
DISPLAY 1.021277 (-15150 8475);
DISPLAY INVISIBLE (-15150 8475);
FORCEPROP 1 LASTPIN (-15025 8425) $PN 1
J 0
(-15013 8437);
DISPLAY 0.787234 (-15013 8437);
PAINT MONO (-15013 8437);
FORCEPROP 1 LASTPIN (-14825 8425) $PN 2
J 0
(-14863 8437);
DISPLAY 0.787234 (-14863 8437);
PAINT MONO (-14863 8437);
FORCEPROP 1 LAST VALUE 33.2
J 2
(-14725 8425);
DISPLAY 0.510638 (-14725 8425);
FORCEPROP 1 LAST TOLERANCE 1%
J 0
(-14700 8425);
DISPLAY 0.510638 (-14700 8425);
FORCEPROP 1 LAST MATERIAL CHIP
J 0
(-14625 8425);
DISPLAY 0.510638 (-14625 8425);
FORCEPROP 2 LAST CDS_LIB pure_quanta
J 0
(-14925 8425);
DISPLAY INVISIBLE (-14925 8425);
FORCEPROP 1 LAST PACK_TYPE 0402LF
J 0
(-15050 8525);
DISPLAY 0.404255 (-15050 8525);
DISPLAY INVISIBLE (-15050 8525);
FORCEPROP 1 LAST WATTAGE 1/16W
J 2
(-14825 8525);
DISPLAY 0.404255 (-14825 8525);
DISPLAY INVISIBLE (-14825 8525);
FORCEPROP 1 LAST PATH I101
J 0
(-14975 8575);
DISPLAY 0.978723 (-14975 8575);
PAINT WHITE (-14975 8575);
DISPLAY INVISIBLE (-14975 8575);
FORCEPROP 1 LAST PART_NUMBER CS03322FB03
J 0
(-15050 8475);
DISPLAY 0.404255 (-15050 8475);
DISPLAY INVISIBLE (-15050 8475);
FORCEADD Q_RES..1
(-14925 8625);
FORCEPROP 1 LAST LOCATION R3239
J 0
(-15150 8625);
DISPLAY 0.638298 (-15150 8625);
FORCEPROP 0 LAST $SEC 1
J 0
(-14975 8725);
DISPLAY 0.680851 (-14975 8725);
PAINT MONO (-14975 8725);
DISPLAY INVISIBLE (-14975 8725);
FORCEPROP 0 LAST CDS_SEC 1
J 0
(-14975 8725);
DISPLAY 1.021277 (-14975 8725);
DISPLAY INVISIBLE (-14975 8725);
FORCEPROP 1 LASTPIN (-15025 8625) $PN 1
J 0
(-15013 8637);
DISPLAY 0.787234 (-15013 8637);
PAINT MONO (-15013 8637);
FORCEPROP 1 LASTPIN (-14825 8625) $PN 2
J 0
(-14863 8637);
DISPLAY 0.787234 (-14863 8637);
PAINT MONO (-14863 8637);
FORCEPROP 1 LAST MATERIAL CHIP
J 0
(-14625 8625);
DISPLAY 0.510638 (-14625 8625);
FORCEPROP 1 LAST VALUE 33.2
J 2
(-14725 8625);
DISPLAY 0.510638 (-14725 8625);
FORCEPROP 1 LAST TOLERANCE 1%
J 0
(-14700 8625);
DISPLAY 0.510638 (-14700 8625);
FORCEPROP 2 LAST CDS_LIB pure_quanta
J 0
(-14925 8625);
DISPLAY INVISIBLE (-14925 8625);
FORCEPROP 1 LAST WATTAGE 1/16W
J 2
(-14825 8725);
DISPLAY 0.404255 (-14825 8725);
DISPLAY INVISIBLE (-14825 8725);
FORCEPROP 1 LAST PACK_TYPE 0402LF
J 0
(-15050 8725);
DISPLAY 0.404255 (-15050 8725);
DISPLAY INVISIBLE (-15050 8725);
FORCEPROP 1 LAST PATH I102
J 0
(-14975 8775);
DISPLAY 0.978723 (-14975 8775);
PAINT WHITE (-14975 8775);
DISPLAY INVISIBLE (-14975 8775);
FORCEPROP 1 LAST PART_NUMBER CS03322FB03
J 0
(-15050 8675);
DISPLAY 0.404255 (-15050 8675);
DISPLAY INVISIBLE (-15050 8675);
FORCEADD Q_RES..1
(-14925 8675);
FORCEPROP 1 LAST LOCATION R3238
J 0
(-15150 8675);
DISPLAY 0.638298 (-15150 8675);
FORCEPROP 0 LAST $SEC 1
J 0
(-14975 8775);
DISPLAY 0.680851 (-14975 8775);
PAINT MONO (-14975 8775);
DISPLAY INVISIBLE (-14975 8775);
FORCEPROP 0 LAST CDS_SEC 1
J 0
(-14975 8775);
DISPLAY 1.021277 (-14975 8775);
DISPLAY INVISIBLE (-14975 8775);
FORCEPROP 1 LASTPIN (-15025 8675) $PN 1
J 0
(-15013 8687);
DISPLAY 0.787234 (-15013 8687);
PAINT MONO (-15013 8687);
FORCEPROP 1 LASTPIN (-14825 8675) $PN 2
J 0
(-14863 8687);
DISPLAY 0.787234 (-14863 8687);
PAINT MONO (-14863 8687);
FORCEPROP 1 LAST VALUE 33.2
J 2
(-14725 8675);
DISPLAY 0.510638 (-14725 8675);
FORCEPROP 1 LAST MATERIAL CHIP
J 0
(-14625 8675);
DISPLAY 0.510638 (-14625 8675);
FORCEPROP 1 LAST TOLERANCE 1%
J 0
(-14700 8675);
DISPLAY 0.510638 (-14700 8675);
FORCEPROP 2 LAST CDS_LIB pure_quanta
J 0
(-14925 8675);
DISPLAY INVISIBLE (-14925 8675);
FORCEPROP 1 LAST WATTAGE 1/16W
J 2
(-14825 8775);
DISPLAY 0.404255 (-14825 8775);
DISPLAY INVISIBLE (-14825 8775);
FORCEPROP 1 LAST PACK_TYPE 0402LF
J 0
(-15050 8775);
DISPLAY 0.404255 (-15050 8775);
DISPLAY INVISIBLE (-15050 8775);
FORCEPROP 1 LAST PATH I103
J 0
(-14975 8825);
DISPLAY 0.978723 (-14975 8825);
PAINT WHITE (-14975 8825);
DISPLAY INVISIBLE (-14975 8825);
FORCEPROP 1 LAST PART_NUMBER CS03322FB03
J 0
(-15050 8725);
DISPLAY 0.404255 (-15050 8725);
DISPLAY INVISIBLE (-15050 8725);
FORCEADD Q_RES..1
(-14925 8575);
FORCEPROP 1 LAST LOCATION R2419
J 0
(-15150 8575);
DISPLAY 0.638298 (-15150 8575);
FORCEPROP 0 LAST $SEC 1
J 0
(-14825 8700);
DISPLAY 0.680851 (-14825 8700);
PAINT MONO (-14825 8700);
DISPLAY INVISIBLE (-14825 8700);
FORCEPROP 0 LAST CDS_SEC 1
J 0
(-14825 8700);
DISPLAY 1.021277 (-14825 8700);
DISPLAY INVISIBLE (-14825 8700);
FORCEPROP 1 LASTPIN (-15025 8575) $PN 1
J 0
(-15013 8587);
DISPLAY 0.787234 (-15013 8587);
PAINT MONO (-15013 8587);
FORCEPROP 1 LASTPIN (-14825 8575) $PN 2
J 0
(-14863 8587);
DISPLAY 0.787234 (-14863 8587);
PAINT MONO (-14863 8587);
FORCEPROP 1 LAST PACK_TYPE 0402LF
J 0
(-15025 8275);
DISPLAY 0.404255 (-15025 8275);
FORCEPROP 1 LAST WATTAGE 1/16W
J 2
(-14800 8275);
DISPLAY 0.404255 (-14800 8275);
FORCEPROP 1 LAST VALUE 33.2
J 2
(-14725 8575);
DISPLAY 0.510638 (-14725 8575);
FORCEPROP 1 LAST MATERIAL CHIP
J 0
(-14625 8575);
DISPLAY 0.510638 (-14625 8575);
FORCEPROP 1 LAST TOLERANCE 1%
J 0
(-14700 8575);
DISPLAY 0.510638 (-14700 8575);
FORCEPROP 2 LAST CDS_LIB pure_quanta
J 0
(-14925 8575);
DISPLAY INVISIBLE (-14925 8575);
FORCEPROP 1 LAST PATH I104
J 0
(-14975 8725);
DISPLAY 0.978723 (-14975 8725);
PAINT WHITE (-14975 8725);
DISPLAY INVISIBLE (-14975 8725);
FORCEPROP 1 LAST PART_NUMBER CS03322FB03
J 0
(-15025 8225);
DISPLAY 0.404255 (-15025 8225);
DISPLAY INVISIBLE (-15025 8225);
FORCEADD Q_RES..1
(-14925 8525);
FORCEPROP 1 LAST LOCATION R2420
J 0
(-15150 8525);
DISPLAY 0.638298 (-15150 8525);
FORCEPROP 0 LAST $SEC 1
J 0
(-15150 8575);
DISPLAY 0.680851 (-15150 8575);
PAINT MONO (-15150 8575);
DISPLAY INVISIBLE (-15150 8575);
FORCEPROP 0 LAST CDS_SEC 1
J 0
(-15150 8575);
DISPLAY 1.021277 (-15150 8575);
DISPLAY INVISIBLE (-15150 8575);
FORCEPROP 1 LASTPIN (-15025 8525) $PN 1
J 0
(-15013 8537);
DISPLAY 0.787234 (-15013 8537);
PAINT MONO (-15013 8537);
FORCEPROP 1 LASTPIN (-14825 8525) $PN 2
J 0
(-14863 8537);
DISPLAY 0.787234 (-14863 8537);
PAINT MONO (-14863 8537);
FORCEPROP 1 LAST MATERIAL CHIP
J 0
(-14625 8525);
DISPLAY 0.510638 (-14625 8525);
FORCEPROP 1 LAST TOLERANCE 1%
J 0
(-14700 8525);
DISPLAY 0.510638 (-14700 8525);
FORCEPROP 1 LAST VALUE 33.2
J 2
(-14725 8525);
DISPLAY 0.510638 (-14725 8525);
FORCEPROP 1 LAST WATTAGE 1/16W
J 2
(-14825 8625);
DISPLAY 0.404255 (-14825 8625);
DISPLAY INVISIBLE (-14825 8625);
FORCEPROP 1 LAST PACK_TYPE 0402LF
J 0
(-15050 8625);
DISPLAY 0.404255 (-15050 8625);
DISPLAY INVISIBLE (-15050 8625);
FORCEPROP 2 LAST CDS_LIB pure_quanta
J 0
(-14925 8525);
DISPLAY INVISIBLE (-14925 8525);
FORCEPROP 1 LAST PATH I105
J 0
(-14975 8675);
DISPLAY 0.978723 (-14975 8675);
PAINT WHITE (-14975 8675);
DISPLAY INVISIBLE (-14975 8675);
FORCEPROP 1 LAST PART_NUMBER CS03322FB03
J 0
(-15050 8575);
DISPLAY 0.404255 (-15050 8575);
DISPLAY INVISIBLE (-15050 8575);
FORCEADD OFFPAGE..1
(-14100 7975);
FORCEPROP 2 LAST $XR0 28 
J 0
(-14351 7975);
DISPLAY 0.638298 (-14351 7975);
PAINT MONO (-14351 7975);
FORCEPROP 2 LAST CDS_LIB standard
J 0
(-14100 7975);
DISPLAY INVISIBLE (-14100 7975);
FORCEPROP 1 LAST OFFPAGE TRUE
J 0
(-13775 7850);
DISPLAY 0.872340 (-13775 7850);
PAINT GREEN (-13775 7850);
DISPLAY INVISIBLE (-13775 7850);
FORCEPROP 1 LAST COMMENT_BODY TRUE
J 0
(-13975 7875);
DISPLAY 0.872340 (-13975 7875);
PAINT PEACH (-13975 7875);
DISPLAY INVISIBLE (-13975 7875);
FORCEPROP 2 LAST PATH I106
J 0
(-14050 8050);
DISPLAY 0.680851 (-14050 8050);
DISPLAY INVISIBLE (-14050 8050);
FORCEADD OFFPAGE..1
(-14100 7875);
FORCEPROP 2 LAST $XR0 26 
J 0
(-14351 7875);
DISPLAY 0.638298 (-14351 7875);
PAINT MONO (-14351 7875);
FORCEPROP 2 LAST CDS_LIB standard
J 0
(-14100 7875);
PAINT MONO (-14100 7875);
DISPLAY INVISIBLE (-14100 7875);
FORCEPROP 1 LAST OFFPAGE TRUE
J 0
(-13775 7750);
DISPLAY 0.872340 (-13775 7750);
PAINT GREEN (-13775 7750);
DISPLAY INVISIBLE (-13775 7750);
FORCEPROP 1 LAST COMMENT_BODY TRUE
J 0
(-13975 7775);
DISPLAY 0.872340 (-13975 7775);
PAINT PEACH (-13975 7775);
DISPLAY INVISIBLE (-13975 7775);
FORCEPROP 2 LAST PATH I107
J 0
(-14050 7950);
DISPLAY 0.680851 (-14050 7950);
DISPLAY INVISIBLE (-14050 7950);
FORCEADD OFFPAGE..1
(-14100 7825);
FORCEPROP 2 LAST $XR0 26 
J 0
(-14351 7825);
DISPLAY 0.638298 (-14351 7825);
PAINT MONO (-14351 7825);
FORCEPROP 2 LAST CDS_LIB standard
J 0
(-14100 7825);
PAINT MONO (-14100 7825);
DISPLAY INVISIBLE (-14100 7825);
FORCEPROP 1 LAST OFFPAGE TRUE
J 0
(-13775 7700);
DISPLAY 0.872340 (-13775 7700);
PAINT GREEN (-13775 7700);
DISPLAY INVISIBLE (-13775 7700);
FORCEPROP 1 LAST COMMENT_BODY TRUE
J 0
(-13975 7725);
DISPLAY 0.872340 (-13975 7725);
PAINT PEACH (-13975 7725);
DISPLAY INVISIBLE (-13975 7725);
FORCEPROP 2 LAST PATH I108
J 0
(-14050 7900);
DISPLAY 0.680851 (-14050 7900);
DISPLAY INVISIBLE (-14050 7900);
FORCEADD OFFPAGE..1
(-14100 8025);
FORCEPROP 2 LAST $XR0 28 
J 0
(-14351 8025);
DISPLAY 0.638298 (-14351 8025);
PAINT MONO (-14351 8025);
FORCEPROP 2 LAST CDS_LIB standard
J 0
(-14100 8025);
DISPLAY INVISIBLE (-14100 8025);
FORCEPROP 1 LAST OFFPAGE TRUE
J 0
(-13775 7900);
DISPLAY 0.872340 (-13775 7900);
PAINT GREEN (-13775 7900);
DISPLAY INVISIBLE (-13775 7900);
FORCEPROP 1 LAST COMMENT_BODY TRUE
J 0
(-13975 7925);
DISPLAY 0.872340 (-13975 7925);
PAINT PEACH (-13975 7925);
DISPLAY INVISIBLE (-13975 7925);
FORCEPROP 2 LAST PATH I109
J 0
(-14050 8100);
DISPLAY 0.680851 (-14050 8100);
DISPLAY INVISIBLE (-14050 8100);
FORCEADD OFFPAGE..5
(-16225 6375);
FORCEPROP 2 LAST $XR0 171 
J 0
(-16480 6375);
DISPLAY 0.638298 (-16480 6375);
PAINT MONO (-16480 6375);
FORCEPROP 2 LAST CDS_LIB standard
J 0
(-16225 6375);
DISPLAY INVISIBLE (-16225 6375);
FORCEPROP 1 LAST OFFPAGE TRUE
J 0
(-15900 6250);
DISPLAY 0.872340 (-15900 6250);
PAINT GREEN (-15900 6250);
DISPLAY INVISIBLE (-15900 6250);
FORCEPROP 1 LAST COMMENT_BODY TRUE
J 0
(-16125 6300);
DISPLAY 0.872340 (-16125 6300);
PAINT PEACH (-16125 6300);
DISPLAY INVISIBLE (-16125 6300);
FORCEPROP 2 LAST PATH I11
J 0
(-16175 6450);
DISPLAY 0.680851 (-16175 6450);
DISPLAY INVISIBLE (-16175 6450);
FORCEADD OFFPAGE..6
(-14100 8225);
FORCEPROP 2 LAST $XR1 249 
J 0
(-14500 8225);
DISPLAY 0.638298 (-14500 8225);
PAINT MONO (-14500 8225);
FORCEPROP 2 LAST $XR0 151 
J 0
(-14380 8225);
DISPLAY 0.638298 (-14380 8225);
PAINT MONO (-14380 8225);
FORCEPROP 2 LAST CDS_LIB standard
J 0
(-14100 8225);
PAINT MONO (-14100 8225);
DISPLAY INVISIBLE (-14100 8225);
FORCEPROP 1 LAST OFFPAGE TRUE
J 0
(-13775 8100);
DISPLAY 0.872340 (-13775 8100);
PAINT GREEN (-13775 8100);
DISPLAY INVISIBLE (-13775 8100);
FORCEPROP 1 LAST COMMENT_BODY TRUE
J 0
(-14000 8150);
DISPLAY 0.872340 (-14000 8150);
PAINT PEACH (-14000 8150);
DISPLAY INVISIBLE (-14000 8150);
FORCEPROP 2 LAST PATH I110
J 0
(-14050 8300);
DISPLAY 0.680851 (-14050 8300);
DISPLAY INVISIBLE (-14050 8300);
FORCEADD OFFPAGE..6
(-14100 8275);
FORCEPROP 2 LAST $XR1 249 
J 0
(-14500 8275);
DISPLAY 0.638298 (-14500 8275);
PAINT MONO (-14500 8275);
FORCEPROP 2 LAST $XR0 151 
J 0
(-14380 8275);
DISPLAY 0.638298 (-14380 8275);
PAINT MONO (-14380 8275);
FORCEPROP 2 LAST CDS_LIB standard
J 0
(-14100 8275);
DISPLAY INVISIBLE (-14100 8275);
FORCEPROP 1 LAST OFFPAGE TRUE
J 0
(-13775 8150);
DISPLAY 0.872340 (-13775 8150);
PAINT GREEN (-13775 8150);
DISPLAY INVISIBLE (-13775 8150);
FORCEPROP 1 LAST COMMENT_BODY TRUE
J 0
(-14000 8200);
DISPLAY 0.872340 (-14000 8200);
PAINT PEACH (-14000 8200);
DISPLAY INVISIBLE (-14000 8200);
FORCEPROP 2 LAST PATH I111
J 0
(-14050 8350);
DISPLAY 0.680851 (-14050 8350);
DISPLAY INVISIBLE (-14050 8350);
FORCEADD OFFPAGE..5
(-14100 6875);
FORCEPROP 2 LAST $XR0 171 
J 0
(-14355 6875);
DISPLAY 0.638298 (-14355 6875);
PAINT MONO (-14355 6875);
FORCEPROP 2 LAST CDS_LIB standard
J 0
(-14100 6875);
DISPLAY INVISIBLE (-14100 6875);
FORCEPROP 1 LAST OFFPAGE TRUE
J 0
(-13775 6750);
DISPLAY 0.872340 (-13775 6750);
PAINT GREEN (-13775 6750);
DISPLAY INVISIBLE (-13775 6750);
FORCEPROP 1 LAST COMMENT_BODY TRUE
J 0
(-14000 6800);
DISPLAY 0.872340 (-14000 6800);
PAINT PEACH (-14000 6800);
DISPLAY INVISIBLE (-14000 6800);
FORCEPROP 2 LAST PATH I112
J 0
(-14050 6950);
DISPLAY 0.680851 (-14050 6950);
DISPLAY INVISIBLE (-14050 6950);
FORCEADD OFFPAGE..5
(-14100 7725);
FORCEPROP 2 LAST $XR0 26 
J 0
(-14324 7725);
DISPLAY 0.638298 (-14324 7725);
PAINT MONO (-14324 7725);
FORCEPROP 2 LAST CDS_LIB standard
J 0
(-14100 7725);
DISPLAY INVISIBLE (-14100 7725);
FORCEPROP 1 LAST OFFPAGE TRUE
J 0
(-13775 7600);
DISPLAY 0.872340 (-13775 7600);
PAINT GREEN (-13775 7600);
DISPLAY INVISIBLE (-13775 7600);
FORCEPROP 1 LAST COMMENT_BODY TRUE
J 0
(-14000 7650);
DISPLAY 0.872340 (-14000 7650);
PAINT PEACH (-14000 7650);
DISPLAY INVISIBLE (-14000 7650);
FORCEPROP 2 LAST PATH I113
J 0
(-14050 7800);
DISPLAY 0.680851 (-14050 7800);
DISPLAY INVISIBLE (-14050 7800);
FORCEADD OFFPAGE..5
(-14100 7675);
FORCEPROP 2 LAST $XR0 26 
J 0
(-14324 7675);
DISPLAY 0.638298 (-14324 7675);
PAINT MONO (-14324 7675);
FORCEPROP 2 LAST CDS_LIB standard
J 0
(-14100 7675);
DISPLAY INVISIBLE (-14100 7675);
FORCEPROP 1 LAST OFFPAGE TRUE
J 0
(-13775 7550);
DISPLAY 0.872340 (-13775 7550);
PAINT GREEN (-13775 7550);
DISPLAY INVISIBLE (-13775 7550);
FORCEPROP 1 LAST COMMENT_BODY TRUE
J 0
(-14000 7600);
DISPLAY 0.872340 (-14000 7600);
PAINT PEACH (-14000 7600);
DISPLAY INVISIBLE (-14000 7600);
FORCEPROP 2 LAST PATH I114
J 0
(-14050 7750);
DISPLAY 0.680851 (-14050 7750);
DISPLAY INVISIBLE (-14050 7750);
FORCEADD OFFPAGE..5
(-14100 6925);
FORCEPROP 2 LAST $XR0 171 
J 0
(-14355 6925);
DISPLAY 0.638298 (-14355 6925);
PAINT MONO (-14355 6925);
FORCEPROP 2 LAST CDS_LIB standard
J 0
(-14100 6925);
DISPLAY INVISIBLE (-14100 6925);
FORCEPROP 1 LAST OFFPAGE TRUE
J 0
(-13775 6800);
DISPLAY 0.872340 (-13775 6800);
PAINT GREEN (-13775 6800);
DISPLAY INVISIBLE (-13775 6800);
FORCEPROP 1 LAST COMMENT_BODY TRUE
J 0
(-14000 6850);
DISPLAY 0.872340 (-14000 6850);
PAINT PEACH (-14000 6850);
DISPLAY INVISIBLE (-14000 6850);
FORCEPROP 2 LAST PATH I115
J 0
(-14050 7000);
DISPLAY 0.680851 (-14050 7000);
DISPLAY INVISIBLE (-14050 7000);
FORCEADD OFFPAGE..5
(-14100 6825);
FORCEPROP 2 LAST $XR0 151 
J 0
(-14355 6825);
DISPLAY 0.638298 (-14355 6825);
PAINT MONO (-14355 6825);
FORCEPROP 2 LAST CDS_LIB standard
J 0
(-14100 6825);
DISPLAY INVISIBLE (-14100 6825);
FORCEPROP 1 LAST OFFPAGE TRUE
J 0
(-13775 6700);
DISPLAY 0.872340 (-13775 6700);
PAINT GREEN (-13775 6700);
DISPLAY INVISIBLE (-13775 6700);
FORCEPROP 1 LAST COMMENT_BODY TRUE
J 0
(-14000 6750);
DISPLAY 0.872340 (-14000 6750);
PAINT PEACH (-14000 6750);
DISPLAY INVISIBLE (-14000 6750);
FORCEPROP 2 LAST PATH I116
J 0
(-14050 6900);
DISPLAY 0.680851 (-14050 6900);
DISPLAY INVISIBLE (-14050 6900);
FORCEADD Q_RES..1
R 2
(-14425 8975);
FORCEPROP 1 LAST LOCATION R6006
J 2
(-14550 8975);
DISPLAY 0.489362 (-14550 8975);
PAINT SKYBLUE (-14550 8975);
FORCEPROP 0 LAST $SEC 1
J 0
(-14550 9025);
DISPLAY 0.680851 (-14550 9025);
PAINT MONO (-14550 9025);
DISPLAY INVISIBLE (-14550 9025);
FORCEPROP 0 LAST CDS_SEC 1
J 0
(-14550 9025);
DISPLAY 1.021277 (-14550 9025);
DISPLAY INVISIBLE (-14550 9025);
FORCEPROP 1 LASTPIN (-14325 8975) $PN 1
J 2
(-14337 8987);
DISPLAY 0.489362 (-14337 8987);
PAINT MONO (-14337 8987);
FORCEPROP 1 LASTPIN (-14525 8975) $PN 2
J 2
(-14487 8987);
DISPLAY 0.489362 (-14487 8987);
PAINT MONO (-14487 8987);
FORCEPROP 1 LAST VALUE 0
J 0
(-14300 8975);
DISPLAY 0.489362 (-14300 8975);
PAINT SKYBLUE (-14300 8975);
FORCEPROP 2 LAST CDS_LIB pure_quanta
J 0
(-14425 8975);
DISPLAY INVISIBLE (-14425 8975);
FORCEPROP 2 LAST BOM_COST MEM
J 0
(-14450 9125);
DISPLAY 0.744681 (-14450 9125);
PAINT WHITE (-14450 9125);
DISPLAY INVISIBLE (-14450 9125);
FORCEPROP 1 LAST WATTAGE 1/16W
J 0
(-14350 8900);
DISPLAY 0.489362 (-14350 8900);
PAINT SKYBLUE (-14350 8900);
DISPLAY INVISIBLE (-14350 8900);
FORCEPROP 1 LAST MATERIAL CHIP
J 0
(-14600 8950);
DISPLAY 0.489362 (-14600 8950);
PAINT SKYBLUE (-14600 8950);
DISPLAY INVISIBLE (-14600 8950);
FORCEPROP 1 LAST TOLERANCE 5%
J 2
(-14300 8950);
DISPLAY 0.489362 (-14300 8950);
PAINT SKYBLUE (-14300 8950);
DISPLAY INVISIBLE (-14300 8950);
FORCEPROP 1 LAST PACK_TYPE 0402LF
J 0
(-14600 8900);
DISPLAY 0.489362 (-14600 8900);
PAINT SKYBLUE (-14600 8900);
DISPLAY INVISIBLE (-14600 8900);
FORCEPROP 1 LAST PATH I117
J 2
(-14375 9125);
DISPLAY 0.978723 (-14375 9125);
PAINT WHITE (-14375 9125);
DISPLAY INVISIBLE (-14375 9125);
FORCEPROP 1 LAST PART_NUMBER CS00002JB13
J 0
(-14525 9025);
DISPLAY 0.489362 (-14525 9025);
PAINT SKYBLUE (-14525 9025);
DISPLAY INVISIBLE (-14525 9025);
FORCEADD Q_RES..1
R 2
(-14425 9025);
FORCEPROP 1 LAST LOCATION R6005
J 2
(-14550 9025);
DISPLAY 0.489362 (-14550 9025);
PAINT SKYBLUE (-14550 9025);
FORCEPROP 0 LAST $SEC 1
J 0
(-14550 9075);
DISPLAY 0.680851 (-14550 9075);
PAINT MONO (-14550 9075);
DISPLAY INVISIBLE (-14550 9075);
FORCEPROP 0 LAST CDS_SEC 1
J 0
(-14550 9075);
DISPLAY 1.021277 (-14550 9075);
DISPLAY INVISIBLE (-14550 9075);
FORCEPROP 1 LASTPIN (-14325 9025) $PN 1
J 2
(-14337 9037);
DISPLAY 0.489362 (-14337 9037);
PAINT MONO (-14337 9037);
FORCEPROP 1 LASTPIN (-14525 9025) $PN 2
J 2
(-14487 9037);
DISPLAY 0.489362 (-14487 9037);
PAINT MONO (-14487 9037);
FORCEPROP 1 LAST VALUE 0
J 0
(-14300 9025);
DISPLAY 0.489362 (-14300 9025);
PAINT SKYBLUE (-14300 9025);
FORCEPROP 1 LAST PACK_TYPE 0402LF
J 0
(-14600 8950);
DISPLAY 0.489362 (-14600 8950);
PAINT SKYBLUE (-14600 8950);
DISPLAY INVISIBLE (-14600 8950);
FORCEPROP 1 LAST TOLERANCE 5%
J 2
(-14300 9000);
DISPLAY 0.489362 (-14300 9000);
PAINT SKYBLUE (-14300 9000);
DISPLAY INVISIBLE (-14300 9000);
FORCEPROP 1 LAST MATERIAL CHIP
J 0
(-14600 9000);
DISPLAY 0.489362 (-14600 9000);
PAINT SKYBLUE (-14600 9000);
DISPLAY INVISIBLE (-14600 9000);
FORCEPROP 1 LAST WATTAGE 1/16W
J 0
(-14350 8950);
DISPLAY 0.489362 (-14350 8950);
PAINT SKYBLUE (-14350 8950);
DISPLAY INVISIBLE (-14350 8950);
FORCEPROP 2 LAST BOM_COST MEM
J 0
(-14450 9175);
DISPLAY 0.744681 (-14450 9175);
PAINT WHITE (-14450 9175);
DISPLAY INVISIBLE (-14450 9175);
FORCEPROP 2 LAST CDS_LIB pure_quanta
J 0
(-14425 9025);
DISPLAY INVISIBLE (-14425 9025);
FORCEPROP 1 LAST PATH I118
J 2
(-14375 9175);
DISPLAY 0.978723 (-14375 9175);
PAINT WHITE (-14375 9175);
DISPLAY INVISIBLE (-14375 9175);
FORCEPROP 1 LAST PART_NUMBER CS00002JB13
J 0
(-14525 9075);
DISPLAY 0.489362 (-14525 9075);
PAINT SKYBLUE (-14525 9075);
DISPLAY INVISIBLE (-14525 9075);
FORCEADD Q_RES..1
R 2
(-14425 8925);
FORCEPROP 1 LAST LOCATION R6007
J 2
(-14550 8925);
DISPLAY 0.489362 (-14550 8925);
PAINT SKYBLUE (-14550 8925);
FORCEPROP 0 LAST $SEC 1
J 0
(-14550 8975);
DISPLAY 0.680851 (-14550 8975);
PAINT MONO (-14550 8975);
DISPLAY INVISIBLE (-14550 8975);
FORCEPROP 0 LAST CDS_SEC 1
J 0
(-14550 8975);
DISPLAY 1.021277 (-14550 8975);
DISPLAY INVISIBLE (-14550 8975);
FORCEPROP 1 LASTPIN (-14325 8925) $PN 1
J 2
(-14337 8937);
DISPLAY 0.489362 (-14337 8937);
PAINT MONO (-14337 8937);
FORCEPROP 1 LASTPIN (-14525 8925) $PN 2
J 2
(-14487 8937);
DISPLAY 0.489362 (-14487 8937);
PAINT MONO (-14487 8937);
FORCEPROP 1 LAST VALUE 0
J 0
(-14300 8925);
DISPLAY 0.489362 (-14300 8925);
PAINT SKYBLUE (-14300 8925);
FORCEPROP 2 LAST CDS_LIB pure_quanta
J 0
(-14425 8925);
DISPLAY INVISIBLE (-14425 8925);
FORCEPROP 2 LAST BOM_COST MEM
J 0
(-14450 9075);
DISPLAY 0.744681 (-14450 9075);
PAINT WHITE (-14450 9075);
DISPLAY INVISIBLE (-14450 9075);
FORCEPROP 1 LAST WATTAGE 1/16W
J 0
(-14350 8850);
DISPLAY 0.489362 (-14350 8850);
PAINT SKYBLUE (-14350 8850);
DISPLAY INVISIBLE (-14350 8850);
FORCEPROP 1 LAST MATERIAL CHIP
J 0
(-14600 8900);
DISPLAY 0.489362 (-14600 8900);
PAINT SKYBLUE (-14600 8900);
DISPLAY INVISIBLE (-14600 8900);
FORCEPROP 1 LAST TOLERANCE 5%
J 2
(-14300 8900);
DISPLAY 0.489362 (-14300 8900);
PAINT SKYBLUE (-14300 8900);
DISPLAY INVISIBLE (-14300 8900);
FORCEPROP 1 LAST PACK_TYPE 0402LF
J 0
(-14600 8850);
DISPLAY 0.489362 (-14600 8850);
PAINT SKYBLUE (-14600 8850);
DISPLAY INVISIBLE (-14600 8850);
FORCEPROP 1 LAST PATH I119
J 2
(-14375 9075);
DISPLAY 0.978723 (-14375 9075);
PAINT WHITE (-14375 9075);
DISPLAY INVISIBLE (-14375 9075);
FORCEPROP 1 LAST PART_NUMBER CS00002JB13
J 0
(-14525 8975);
DISPLAY 0.489362 (-14525 8975);
PAINT SKYBLUE (-14525 8975);
DISPLAY INVISIBLE (-14525 8975);
FORCEADD OFFPAGE..6
(-16200 6575);
FORCEPROP 2 LAST $XR0 151 
J 0
(-16480 6575);
DISPLAY 0.638298 (-16480 6575);
PAINT MONO (-16480 6575);
FORCEPROP 2 LAST CDS_LIB standard
J 0
(-16200 6575);
DISPLAY INVISIBLE (-16200 6575);
FORCEPROP 1 LAST OFFPAGE TRUE
J 0
(-15875 6450);
DISPLAY 0.872340 (-15875 6450);
PAINT GREEN (-15875 6450);
DISPLAY INVISIBLE (-15875 6450);
FORCEPROP 1 LAST COMMENT_BODY TRUE
J 0
(-16100 6500);
DISPLAY 0.872340 (-16100 6500);
PAINT PEACH (-16100 6500);
DISPLAY INVISIBLE (-16100 6500);
FORCEPROP 2 LAST PATH I12
J 0
(-16475 6625);
DISPLAY 0.680851 (-16475 6625);
DISPLAY INVISIBLE (-16475 6625);
FORCEADD Q_RES..1
R 2
(-14425 9075);
FORCEPROP 1 LAST LOCATION R6004
J 2
(-14550 9075);
DISPLAY 0.489362 (-14550 9075);
PAINT SKYBLUE (-14550 9075);
FORCEPROP 0 LAST $SEC 1
J 0
(-14550 9125);
DISPLAY 0.680851 (-14550 9125);
PAINT MONO (-14550 9125);
DISPLAY INVISIBLE (-14550 9125);
FORCEPROP 0 LAST CDS_SEC 1
J 0
(-14550 9125);
DISPLAY 1.021277 (-14550 9125);
DISPLAY INVISIBLE (-14550 9125);
FORCEPROP 1 LASTPIN (-14325 9075) $PN 1
J 2
(-14337 9087);
DISPLAY 0.489362 (-14337 9087);
PAINT MONO (-14337 9087);
FORCEPROP 1 LASTPIN (-14525 9075) $PN 2
J 2
(-14487 9087);
DISPLAY 0.489362 (-14487 9087);
PAINT MONO (-14487 9087);
FORCEPROP 1 LAST VALUE 0
J 0
(-14300 9075);
DISPLAY 0.489362 (-14300 9075);
PAINT SKYBLUE (-14300 9075);
FORCEPROP 1 LAST PACK_TYPE 0402LF
J 0
(-14600 9000);
DISPLAY 0.489362 (-14600 9000);
PAINT SKYBLUE (-14600 9000);
DISPLAY INVISIBLE (-14600 9000);
FORCEPROP 1 LAST TOLERANCE 5%
J 2
(-14300 9050);
DISPLAY 0.489362 (-14300 9050);
PAINT SKYBLUE (-14300 9050);
DISPLAY INVISIBLE (-14300 9050);
FORCEPROP 1 LAST MATERIAL CHIP
J 0
(-14600 9050);
DISPLAY 0.489362 (-14600 9050);
PAINT SKYBLUE (-14600 9050);
DISPLAY INVISIBLE (-14600 9050);
FORCEPROP 1 LAST WATTAGE 1/16W
J 0
(-14350 9000);
DISPLAY 0.489362 (-14350 9000);
PAINT SKYBLUE (-14350 9000);
DISPLAY INVISIBLE (-14350 9000);
FORCEPROP 2 LAST BOM_COST MEM
J 0
(-14450 9225);
DISPLAY 0.744681 (-14450 9225);
PAINT WHITE (-14450 9225);
DISPLAY INVISIBLE (-14450 9225);
FORCEPROP 2 LAST CDS_LIB pure_quanta
J 0
(-14425 9075);
DISPLAY INVISIBLE (-14425 9075);
FORCEPROP 1 LAST PATH I120
J 2
(-14375 9225);
DISPLAY 0.978723 (-14375 9225);
PAINT WHITE (-14375 9225);
DISPLAY INVISIBLE (-14375 9225);
FORCEPROP 1 LAST PART_NUMBER CS00002JB13
J 0
(-14525 9125);
DISPLAY 0.489362 (-14525 9125);
PAINT SKYBLUE (-14525 9125);
DISPLAY INVISIBLE (-14525 9125);
FORCEADD Q_RES..1
R 2
(-14425 9125);
FORCEPROP 1 LAST LOCATION R6003
J 2
(-14550 9125);
DISPLAY 0.489362 (-14550 9125);
PAINT SKYBLUE (-14550 9125);
FORCEPROP 0 LAST $SEC 1
J 0
(-14550 9175);
DISPLAY 0.680851 (-14550 9175);
PAINT MONO (-14550 9175);
DISPLAY INVISIBLE (-14550 9175);
FORCEPROP 0 LAST CDS_SEC 1
J 0
(-14550 9175);
DISPLAY 1.021277 (-14550 9175);
DISPLAY INVISIBLE (-14550 9175);
FORCEPROP 1 LASTPIN (-14325 9125) $PN 1
J 2
(-14337 9137);
DISPLAY 0.489362 (-14337 9137);
PAINT MONO (-14337 9137);
FORCEPROP 1 LASTPIN (-14525 9125) $PN 2
J 2
(-14487 9137);
DISPLAY 0.489362 (-14487 9137);
PAINT MONO (-14487 9137);
FORCEPROP 1 LAST VALUE 0
J 0
(-14300 9125);
DISPLAY 0.489362 (-14300 9125);
PAINT SKYBLUE (-14300 9125);
FORCEPROP 1 LAST PACK_TYPE 0402LF
J 0
(-14600 9050);
DISPLAY 0.489362 (-14600 9050);
PAINT SKYBLUE (-14600 9050);
DISPLAY INVISIBLE (-14600 9050);
FORCEPROP 1 LAST TOLERANCE 5%
J 2
(-14300 9100);
DISPLAY 0.489362 (-14300 9100);
PAINT SKYBLUE (-14300 9100);
DISPLAY INVISIBLE (-14300 9100);
FORCEPROP 1 LAST MATERIAL CHIP
J 0
(-14600 9100);
DISPLAY 0.489362 (-14600 9100);
PAINT SKYBLUE (-14600 9100);
DISPLAY INVISIBLE (-14600 9100);
FORCEPROP 1 LAST WATTAGE 1/16W
J 0
(-14350 9050);
DISPLAY 0.489362 (-14350 9050);
PAINT SKYBLUE (-14350 9050);
DISPLAY INVISIBLE (-14350 9050);
FORCEPROP 2 LAST BOM_COST MEM
J 0
(-14450 9275);
DISPLAY 0.744681 (-14450 9275);
PAINT WHITE (-14450 9275);
DISPLAY INVISIBLE (-14450 9275);
FORCEPROP 2 LAST CDS_LIB pure_quanta
J 0
(-14425 9125);
DISPLAY INVISIBLE (-14425 9125);
FORCEPROP 1 LAST PATH I121
J 2
(-14375 9275);
DISPLAY 0.978723 (-14375 9275);
PAINT WHITE (-14375 9275);
DISPLAY INVISIBLE (-14375 9275);
FORCEPROP 1 LAST PART_NUMBER CS00002JB13
J 0
(-14525 9175);
DISPLAY 0.489362 (-14525 9175);
PAINT SKYBLUE (-14525 9175);
DISPLAY INVISIBLE (-14525 9175);
FORCEADD Q_RES..1
R 2
(-14425 9175);
FORCEPROP 1 LAST LOCATION R6002
J 2
(-14550 9175);
DISPLAY 0.489362 (-14550 9175);
PAINT SKYBLUE (-14550 9175);
FORCEPROP 0 LAST $SEC 1
J 0
(-14550 9225);
DISPLAY 0.680851 (-14550 9225);
PAINT MONO (-14550 9225);
DISPLAY INVISIBLE (-14550 9225);
FORCEPROP 0 LAST CDS_SEC 1
J 0
(-14550 9225);
DISPLAY 1.021277 (-14550 9225);
DISPLAY INVISIBLE (-14550 9225);
FORCEPROP 1 LASTPIN (-14325 9175) $PN 1
J 2
(-14337 9187);
DISPLAY 0.489362 (-14337 9187);
PAINT MONO (-14337 9187);
FORCEPROP 1 LASTPIN (-14525 9175) $PN 2
J 2
(-14487 9187);
DISPLAY 0.489362 (-14487 9187);
PAINT MONO (-14487 9187);
FORCEPROP 1 LAST VALUE 0
J 0
(-14300 9175);
DISPLAY 0.489362 (-14300 9175);
PAINT SKYBLUE (-14300 9175);
FORCEPROP 1 LAST PACK_TYPE 0402LF
J 0
(-14600 9100);
DISPLAY 0.489362 (-14600 9100);
PAINT SKYBLUE (-14600 9100);
DISPLAY INVISIBLE (-14600 9100);
FORCEPROP 1 LAST TOLERANCE 5%
J 2
(-14300 9150);
DISPLAY 0.489362 (-14300 9150);
PAINT SKYBLUE (-14300 9150);
DISPLAY INVISIBLE (-14300 9150);
FORCEPROP 1 LAST MATERIAL CHIP
J 0
(-14600 9150);
DISPLAY 0.489362 (-14600 9150);
PAINT SKYBLUE (-14600 9150);
DISPLAY INVISIBLE (-14600 9150);
FORCEPROP 1 LAST WATTAGE 1/16W
J 0
(-14350 9100);
DISPLAY 0.489362 (-14350 9100);
PAINT SKYBLUE (-14350 9100);
DISPLAY INVISIBLE (-14350 9100);
FORCEPROP 2 LAST BOM_COST MEM
J 0
(-14450 9325);
DISPLAY 0.744681 (-14450 9325);
PAINT WHITE (-14450 9325);
DISPLAY INVISIBLE (-14450 9325);
FORCEPROP 2 LAST CDS_LIB pure_quanta
J 0
(-14425 9175);
DISPLAY INVISIBLE (-14425 9175);
FORCEPROP 1 LAST PATH I122
J 2
(-14375 9325);
DISPLAY 0.978723 (-14375 9325);
PAINT WHITE (-14375 9325);
DISPLAY INVISIBLE (-14375 9325);
FORCEPROP 1 LAST PART_NUMBER CS00002JB13
J 0
(-14525 9225);
DISPLAY 0.489362 (-14525 9225);
PAINT SKYBLUE (-14525 9225);
DISPLAY INVISIBLE (-14525 9225);
FORCEADD Q_RES..1
R 2
(-14425 9275);
FORCEPROP 1 LAST LOCATION R6000
J 2
(-14550 9275);
DISPLAY 0.489362 (-14550 9275);
PAINT SKYBLUE (-14550 9275);
FORCEPROP 0 LAST $SEC 1
J 0
(-14550 9325);
DISPLAY 0.680851 (-14550 9325);
PAINT MONO (-14550 9325);
DISPLAY INVISIBLE (-14550 9325);
FORCEPROP 0 LAST CDS_SEC 1
J 0
(-14550 9325);
DISPLAY 1.021277 (-14550 9325);
DISPLAY INVISIBLE (-14550 9325);
FORCEPROP 1 LASTPIN (-14325 9275) $PN 1
J 2
(-14337 9287);
DISPLAY 0.489362 (-14337 9287);
PAINT MONO (-14337 9287);
FORCEPROP 1 LASTPIN (-14525 9275) $PN 2
J 2
(-14487 9287);
DISPLAY 0.489362 (-14487 9287);
PAINT MONO (-14487 9287);
FORCEPROP 1 LAST VALUE 0
J 0
(-14300 9275);
DISPLAY 0.489362 (-14300 9275);
PAINT SKYBLUE (-14300 9275);
FORCEPROP 1 LAST PACK_TYPE 0402LF
J 0
(-14600 9200);
DISPLAY 0.489362 (-14600 9200);
PAINT SKYBLUE (-14600 9200);
DISPLAY INVISIBLE (-14600 9200);
FORCEPROP 1 LAST TOLERANCE 5%
J 2
(-14300 9250);
DISPLAY 0.489362 (-14300 9250);
PAINT SKYBLUE (-14300 9250);
DISPLAY INVISIBLE (-14300 9250);
FORCEPROP 1 LAST MATERIAL CHIP
J 0
(-14600 9250);
DISPLAY 0.489362 (-14600 9250);
PAINT SKYBLUE (-14600 9250);
DISPLAY INVISIBLE (-14600 9250);
FORCEPROP 1 LAST WATTAGE 1/16W
J 0
(-14350 9200);
DISPLAY 0.489362 (-14350 9200);
PAINT SKYBLUE (-14350 9200);
DISPLAY INVISIBLE (-14350 9200);
FORCEPROP 2 LAST BOM_COST MEM
J 0
(-14450 9425);
DISPLAY 0.744681 (-14450 9425);
PAINT WHITE (-14450 9425);
DISPLAY INVISIBLE (-14450 9425);
FORCEPROP 2 LAST CDS_LIB pure_quanta
J 0
(-14425 9275);
DISPLAY INVISIBLE (-14425 9275);
FORCEPROP 1 LAST PATH I123
J 2
(-14375 9425);
DISPLAY 0.978723 (-14375 9425);
PAINT WHITE (-14375 9425);
DISPLAY INVISIBLE (-14375 9425);
FORCEPROP 1 LAST PART_NUMBER CS00002JB13
J 0
(-14525 9325);
DISPLAY 0.489362 (-14525 9325);
PAINT SKYBLUE (-14525 9325);
DISPLAY INVISIBLE (-14525 9325);
FORCEADD Q_RES..1
R 2
(-14425 9225);
FORCEPROP 1 LAST LOCATION R6001
J 2
(-14550 9225);
DISPLAY 0.489362 (-14550 9225);
PAINT SKYBLUE (-14550 9225);
FORCEPROP 0 LAST $SEC 1
J 0
(-14550 9275);
DISPLAY 0.680851 (-14550 9275);
PAINT MONO (-14550 9275);
DISPLAY INVISIBLE (-14550 9275);
FORCEPROP 0 LAST CDS_SEC 1
J 0
(-14550 9275);
DISPLAY 1.021277 (-14550 9275);
DISPLAY INVISIBLE (-14550 9275);
FORCEPROP 1 LASTPIN (-14325 9225) $PN 1
J 2
(-14337 9237);
DISPLAY 0.489362 (-14337 9237);
PAINT MONO (-14337 9237);
FORCEPROP 1 LASTPIN (-14525 9225) $PN 2
J 2
(-14487 9237);
DISPLAY 0.489362 (-14487 9237);
PAINT MONO (-14487 9237);
FORCEPROP 1 LAST VALUE 0
J 0
(-14300 9225);
DISPLAY 0.489362 (-14300 9225);
PAINT SKYBLUE (-14300 9225);
FORCEPROP 1 LAST PACK_TYPE 0402LF
J 0
(-14600 9150);
DISPLAY 0.489362 (-14600 9150);
PAINT SKYBLUE (-14600 9150);
DISPLAY INVISIBLE (-14600 9150);
FORCEPROP 1 LAST TOLERANCE 5%
J 2
(-14300 9200);
DISPLAY 0.489362 (-14300 9200);
PAINT SKYBLUE (-14300 9200);
DISPLAY INVISIBLE (-14300 9200);
FORCEPROP 1 LAST MATERIAL CHIP
J 0
(-14600 9200);
DISPLAY 0.489362 (-14600 9200);
PAINT SKYBLUE (-14600 9200);
DISPLAY INVISIBLE (-14600 9200);
FORCEPROP 1 LAST WATTAGE 1/16W
J 0
(-14350 9150);
DISPLAY 0.489362 (-14350 9150);
PAINT SKYBLUE (-14350 9150);
DISPLAY INVISIBLE (-14350 9150);
FORCEPROP 2 LAST BOM_COST MEM
J 0
(-14450 9375);
DISPLAY 0.744681 (-14450 9375);
PAINT WHITE (-14450 9375);
DISPLAY INVISIBLE (-14450 9375);
FORCEPROP 2 LAST CDS_LIB pure_quanta
J 0
(-14425 9225);
DISPLAY INVISIBLE (-14425 9225);
FORCEPROP 1 LAST PATH I124
J 2
(-14375 9375);
DISPLAY 0.978723 (-14375 9375);
PAINT WHITE (-14375 9375);
DISPLAY INVISIBLE (-14375 9375);
FORCEPROP 1 LAST PART_NUMBER CS00002JB13
J 0
(-14525 9275);
DISPLAY 0.489362 (-14525 9275);
PAINT SKYBLUE (-14525 9275);
DISPLAY INVISIBLE (-14525 9275);
FORCEADD OFFPAGE..5
(-14100 8825);
FORCEPROP 2 LAST $XR0 80 
J 0
(-14324 8825);
DISPLAY 0.638298 (-14324 8825);
PAINT MONO (-14324 8825);
FORCEPROP 2 LAST CDS_LIB standard
J 0
(-14100 8825);
DISPLAY INVISIBLE (-14100 8825);
FORCEPROP 1 LAST OFFPAGE TRUE
J 0
(-13775 8700);
DISPLAY 0.872340 (-13775 8700);
PAINT GREEN (-13775 8700);
DISPLAY INVISIBLE (-13775 8700);
FORCEPROP 1 LAST COMMENT_BODY TRUE
J 0
(-14000 8750);
DISPLAY 0.872340 (-14000 8750);
PAINT PEACH (-14000 8750);
DISPLAY INVISIBLE (-14000 8750);
FORCEPROP 2 LAST PATH I125
J 0
(-14050 8900);
DISPLAY 0.680851 (-14050 8900);
DISPLAY INVISIBLE (-14050 8900);
FORCEADD UNIVERSAL_POWER..1
(-12925 9750);
FORCEPROP 3 LASTPIN (-12925 9700) SIG_NAME P12V_SCM\g
J 0
(-12915 9710);
DISPLAY 0.659574 (-12915 9710);
PAINT MONO (-12915 9710);
DISPLAY INVISIBLE (-12915 9710);
FORCEPROP 1 LAST HDL_POWER P12V_SCM
J 1
(-12925 9800);
DISPLAY 0.702128 (-12925 9800);
PAINT GREEN (-12925 9800);
FORCEPROP 2 LAST CDS_LIB pure_quanta_power
J 0
(-12925 9750);
DISPLAY INVISIBLE (-12925 9750);
FORCEPROP 1 LAST PATH I126
J 0
(-12875 9775);
DISPLAY 0.872340 (-12875 9775);
PAINT AQUA (-12875 9775);
DISPLAY INVISIBLE (-12875 9775);
FORCEADD UNIVERSAL_POWER..1
(-11200 9750);
FORCEPROP 3 LASTPIN (-11200 9700) SIG_NAME P12V_SCM\g
J 0
(-11190 9710);
DISPLAY 0.659574 (-11190 9710);
PAINT MONO (-11190 9710);
DISPLAY INVISIBLE (-11190 9710);
FORCEPROP 1 LAST HDL_POWER P12V_SCM
J 1
(-11200 9800);
DISPLAY 0.702128 (-11200 9800);
PAINT GREEN (-11200 9800);
FORCEPROP 2 LAST CDS_LIB pure_quanta_power
J 0
(-11200 9750);
DISPLAY INVISIBLE (-11200 9750);
FORCEPROP 1 LAST PATH I127
J 0
(-11150 9775);
DISPLAY 0.872340 (-11150 9775);
PAINT AQUA (-11150 9775);
DISPLAY INVISIBLE (-11150 9775);
FORCEADD Q_RES..1
R 2
(-10300 6825);
FORCEPROP 1 LAST LOCATION R6014
J 2
(-10100 6825);
DISPLAY 0.489362 (-10100 6825);
PAINT SKYBLUE (-10100 6825);
FORCEPROP 0 LAST $SEC 1
J 0
(-10100 6850);
DISPLAY 0.680851 (-10100 6850);
PAINT MONO (-10100 6850);
DISPLAY INVISIBLE (-10100 6850);
FORCEPROP 0 LAST CDS_SEC 1
J 0
(-10100 6850);
DISPLAY 0.680851 (-10100 6850);
DISPLAY INVISIBLE (-10100 6850);
FORCEPROP 1 LASTPIN (-10200 6825) $PN 1
J 2
(-10212 6837);
DISPLAY 0.787234 (-10212 6837);
PAINT MONO (-10212 6837);
FORCEPROP 1 LASTPIN (-10400 6825) $PN 2
J 2
(-10362 6837);
DISPLAY 0.787234 (-10362 6837);
PAINT MONO (-10362 6837);
FORCEPROP 1 LAST VALUE 0
J 0
(-10450 6825);
DISPLAY 0.489362 (-10450 6825);
PAINT SKYBLUE (-10450 6825);
FORCEPROP 2 LAST CDS_LIB pure_quanta
J 0
(-10300 6825);
DISPLAY INVISIBLE (-10300 6825);
FORCEPROP 2 LAST BOM_COST MEM
J 0
(-10325 6975);
DISPLAY 0.744681 (-10325 6975);
PAINT WHITE (-10325 6975);
DISPLAY INVISIBLE (-10325 6975);
FORCEPROP 1 LAST WATTAGE 1/16W
J 0
(-10225 6750);
DISPLAY 0.489362 (-10225 6750);
PAINT SKYBLUE (-10225 6750);
DISPLAY INVISIBLE (-10225 6750);
FORCEPROP 1 LAST MATERIAL CHIP
J 0
(-10475 6800);
DISPLAY 0.489362 (-10475 6800);
PAINT SKYBLUE (-10475 6800);
DISPLAY INVISIBLE (-10475 6800);
FORCEPROP 1 LAST TOLERANCE 5%
J 2
(-10175 6800);
DISPLAY 0.489362 (-10175 6800);
PAINT SKYBLUE (-10175 6800);
DISPLAY INVISIBLE (-10175 6800);
FORCEPROP 1 LAST PACK_TYPE 0402LF
J 0
(-10475 6750);
DISPLAY 0.489362 (-10475 6750);
PAINT SKYBLUE (-10475 6750);
DISPLAY INVISIBLE (-10475 6750);
FORCEPROP 1 LAST PATH I128
J 2
(-10250 6975);
DISPLAY 0.978723 (-10250 6975);
PAINT WHITE (-10250 6975);
DISPLAY INVISIBLE (-10250 6975);
FORCEPROP 1 LAST PART_NUMBER CS00002JB13
J 0
(-10400 6875);
DISPLAY 0.489362 (-10400 6875);
PAINT SKYBLUE (-10400 6875);
DISPLAY INVISIBLE (-10400 6875);
FORCEADD Q_RES..1
R 2
(-10300 6775);
FORCEPROP 1 LAST LOCATION R6015
J 2
(-10100 6775);
DISPLAY 0.489362 (-10100 6775);
PAINT SKYBLUE (-10100 6775);
FORCEPROP 0 LAST $SEC 1
J 0
(-10100 6800);
DISPLAY 0.680851 (-10100 6800);
PAINT MONO (-10100 6800);
DISPLAY INVISIBLE (-10100 6800);
FORCEPROP 0 LAST CDS_SEC 1
J 0
(-10100 6800);
DISPLAY 0.680851 (-10100 6800);
DISPLAY INVISIBLE (-10100 6800);
FORCEPROP 1 LASTPIN (-10200 6775) $PN 1
J 2
(-10212 6787);
DISPLAY 0.787234 (-10212 6787);
PAINT MONO (-10212 6787);
FORCEPROP 1 LASTPIN (-10400 6775) $PN 2
J 2
(-10362 6787);
DISPLAY 0.787234 (-10362 6787);
PAINT MONO (-10362 6787);
FORCEPROP 1 LAST VALUE 0
J 0
(-10450 6775);
DISPLAY 0.489362 (-10450 6775);
PAINT SKYBLUE (-10450 6775);
FORCEPROP 2 LAST CDS_LIB pure_quanta
J 0
(-10300 6775);
DISPLAY INVISIBLE (-10300 6775);
FORCEPROP 2 LAST BOM_COST MEM
J 0
(-10325 6925);
DISPLAY 0.744681 (-10325 6925);
PAINT WHITE (-10325 6925);
DISPLAY INVISIBLE (-10325 6925);
FORCEPROP 1 LAST WATTAGE 1/16W
J 0
(-10225 6700);
DISPLAY 0.489362 (-10225 6700);
PAINT SKYBLUE (-10225 6700);
DISPLAY INVISIBLE (-10225 6700);
FORCEPROP 1 LAST MATERIAL CHIP
J 0
(-10475 6750);
DISPLAY 0.489362 (-10475 6750);
PAINT SKYBLUE (-10475 6750);
DISPLAY INVISIBLE (-10475 6750);
FORCEPROP 1 LAST TOLERANCE 5%
J 2
(-10175 6750);
DISPLAY 0.489362 (-10175 6750);
PAINT SKYBLUE (-10175 6750);
DISPLAY INVISIBLE (-10175 6750);
FORCEPROP 1 LAST PACK_TYPE 0402LF
J 0
(-10475 6700);
DISPLAY 0.489362 (-10475 6700);
PAINT SKYBLUE (-10475 6700);
DISPLAY INVISIBLE (-10475 6700);
FORCEPROP 1 LAST PATH I129
J 2
(-10250 6925);
DISPLAY 0.978723 (-10250 6925);
PAINT WHITE (-10250 6925);
DISPLAY INVISIBLE (-10250 6925);
FORCEPROP 1 LAST PART_NUMBER CS00002JB13
J 0
(-10400 6825);
DISPLAY 0.489362 (-10400 6825);
PAINT SKYBLUE (-10400 6825);
DISPLAY INVISIBLE (-10400 6825);
FORCEADD Q_RES..1
R 2
(-10300 6875);
FORCEPROP 1 LAST LOCATION R6013
J 2
(-10100 6875);
DISPLAY 0.489362 (-10100 6875);
PAINT SKYBLUE (-10100 6875);
FORCEPROP 0 LAST $SEC 1
J 0
(-10100 6900);
DISPLAY 0.680851 (-10100 6900);
PAINT MONO (-10100 6900);
DISPLAY INVISIBLE (-10100 6900);
FORCEPROP 0 LAST CDS_SEC 1
J 0
(-10100 6900);
DISPLAY 0.680851 (-10100 6900);
DISPLAY INVISIBLE (-10100 6900);
FORCEPROP 1 LASTPIN (-10200 6875) $PN 1
J 2
(-10212 6887);
DISPLAY 0.787234 (-10212 6887);
PAINT MONO (-10212 6887);
FORCEPROP 1 LASTPIN (-10400 6875) $PN 2
J 2
(-10362 6887);
DISPLAY 0.787234 (-10362 6887);
PAINT MONO (-10362 6887);
FORCEPROP 1 LAST VALUE 0
J 0
(-10450 6875);
DISPLAY 0.489362 (-10450 6875);
PAINT SKYBLUE (-10450 6875);
FORCEPROP 1 LAST PACK_TYPE 0402LF
J 0
(-10475 6800);
DISPLAY 0.489362 (-10475 6800);
PAINT SKYBLUE (-10475 6800);
DISPLAY INVISIBLE (-10475 6800);
FORCEPROP 1 LAST TOLERANCE 5%
J 2
(-10175 6850);
DISPLAY 0.489362 (-10175 6850);
PAINT SKYBLUE (-10175 6850);
DISPLAY INVISIBLE (-10175 6850);
FORCEPROP 1 LAST MATERIAL CHIP
J 0
(-10475 6850);
DISPLAY 0.489362 (-10475 6850);
PAINT SKYBLUE (-10475 6850);
DISPLAY INVISIBLE (-10475 6850);
FORCEPROP 1 LAST WATTAGE 1/16W
J 0
(-10225 6800);
DISPLAY 0.489362 (-10225 6800);
PAINT SKYBLUE (-10225 6800);
DISPLAY INVISIBLE (-10225 6800);
FORCEPROP 2 LAST BOM_COST MEM
J 0
(-10325 7025);
DISPLAY 0.744681 (-10325 7025);
PAINT WHITE (-10325 7025);
DISPLAY INVISIBLE (-10325 7025);
FORCEPROP 2 LAST CDS_LIB pure_quanta
J 0
(-10300 6875);
DISPLAY INVISIBLE (-10300 6875);
FORCEPROP 1 LAST PATH I130
J 2
(-10250 7025);
DISPLAY 0.978723 (-10250 7025);
PAINT WHITE (-10250 7025);
DISPLAY INVISIBLE (-10250 7025);
FORCEPROP 1 LAST PART_NUMBER CS00002JB13
J 0
(-10400 6925);
DISPLAY 0.489362 (-10400 6925);
PAINT SKYBLUE (-10400 6925);
DISPLAY INVISIBLE (-10400 6925);
FORCEADD Q_RES..1
R 2
(-10300 6925);
FORCEPROP 1 LAST LOCATION R6012
J 2
(-10100 6925);
DISPLAY 0.489362 (-10100 6925);
PAINT SKYBLUE (-10100 6925);
FORCEPROP 0 LAST $SEC 1
J 0
(-10150 6975);
DISPLAY 0.680851 (-10150 6975);
PAINT MONO (-10150 6975);
DISPLAY INVISIBLE (-10150 6975);
FORCEPROP 0 LAST CDS_SEC 1
J 0
(-10150 6975);
DISPLAY 0.680851 (-10150 6975);
DISPLAY INVISIBLE (-10150 6975);
FORCEPROP 1 LASTPIN (-10200 6925) $PN 1
J 2
(-10212 6937);
DISPLAY 0.489362 (-10212 6937);
PAINT MONO (-10212 6937);
FORCEPROP 1 LASTPIN (-10400 6925) $PN 2
J 2
(-10362 6937);
DISPLAY 0.489362 (-10362 6937);
PAINT MONO (-10362 6937);
FORCEPROP 1 LAST VALUE 0
J 0
(-10450 6925);
DISPLAY 0.489362 (-10450 6925);
PAINT SKYBLUE (-10450 6925);
FORCEPROP 2 LAST CDS_LIB pure_quanta
J 0
(-10300 6925);
DISPLAY INVISIBLE (-10300 6925);
FORCEPROP 2 LAST BOM_COST MEM
J 0
(-10325 7075);
DISPLAY 0.744681 (-10325 7075);
PAINT WHITE (-10325 7075);
DISPLAY INVISIBLE (-10325 7075);
FORCEPROP 1 LAST WATTAGE 1/16W
J 0
(-10225 6850);
DISPLAY 0.489362 (-10225 6850);
PAINT SKYBLUE (-10225 6850);
DISPLAY INVISIBLE (-10225 6850);
FORCEPROP 1 LAST MATERIAL CHIP
J 0
(-10475 6900);
DISPLAY 0.489362 (-10475 6900);
PAINT SKYBLUE (-10475 6900);
DISPLAY INVISIBLE (-10475 6900);
FORCEPROP 1 LAST TOLERANCE 5%
J 2
(-10175 6900);
DISPLAY 0.489362 (-10175 6900);
PAINT SKYBLUE (-10175 6900);
DISPLAY INVISIBLE (-10175 6900);
FORCEPROP 1 LAST PACK_TYPE 0402LF
J 0
(-10475 6850);
DISPLAY 0.489362 (-10475 6850);
PAINT SKYBLUE (-10475 6850);
DISPLAY INVISIBLE (-10475 6850);
FORCEPROP 1 LAST PATH I131
J 2
(-10250 7075);
DISPLAY 0.978723 (-10250 7075);
PAINT WHITE (-10250 7075);
DISPLAY INVISIBLE (-10250 7075);
FORCEPROP 1 LAST PART_NUMBER CS00002JB13
J 0
(-10400 6975);
DISPLAY 0.489362 (-10400 6975);
PAINT SKYBLUE (-10400 6975);
DISPLAY INVISIBLE (-10400 6975);
FORCEADD Q_RES..1
R 2
(-10300 7025);
FORCEPROP 1 LAST LOCATION R6011
J 2
(-10100 7025);
DISPLAY 0.489362 (-10100 7025);
PAINT SKYBLUE (-10100 7025);
FORCEPROP 0 LAST $SEC 1
J 0
(-10100 7050);
DISPLAY 0.680851 (-10100 7050);
PAINT MONO (-10100 7050);
DISPLAY INVISIBLE (-10100 7050);
FORCEPROP 0 LAST CDS_SEC 1
J 0
(-10100 7050);
DISPLAY 0.680851 (-10100 7050);
DISPLAY INVISIBLE (-10100 7050);
FORCEPROP 1 LASTPIN (-10200 7025) $PN 1
J 2
(-10212 7037);
DISPLAY 0.787234 (-10212 7037);
PAINT MONO (-10212 7037);
FORCEPROP 1 LASTPIN (-10400 7025) $PN 2
J 2
(-10362 7037);
DISPLAY 0.787234 (-10362 7037);
PAINT MONO (-10362 7037);
FORCEPROP 1 LAST VALUE 0
J 0
(-10450 7025);
DISPLAY 0.489362 (-10450 7025);
PAINT SKYBLUE (-10450 7025);
FORCEPROP 1 LAST PACK_TYPE 0402LF
J 0
(-10475 6950);
DISPLAY 0.489362 (-10475 6950);
PAINT SKYBLUE (-10475 6950);
DISPLAY INVISIBLE (-10475 6950);
FORCEPROP 1 LAST TOLERANCE 5%
J 2
(-10175 7000);
DISPLAY 0.489362 (-10175 7000);
PAINT SKYBLUE (-10175 7000);
DISPLAY INVISIBLE (-10175 7000);
FORCEPROP 1 LAST MATERIAL CHIP
J 0
(-10475 7000);
DISPLAY 0.489362 (-10475 7000);
PAINT SKYBLUE (-10475 7000);
DISPLAY INVISIBLE (-10475 7000);
FORCEPROP 1 LAST WATTAGE 1/16W
J 0
(-10225 6950);
DISPLAY 0.489362 (-10225 6950);
PAINT SKYBLUE (-10225 6950);
DISPLAY INVISIBLE (-10225 6950);
FORCEPROP 2 LAST BOM_COST MEM
J 0
(-10325 7175);
DISPLAY 0.744681 (-10325 7175);
PAINT WHITE (-10325 7175);
DISPLAY INVISIBLE (-10325 7175);
FORCEPROP 2 LAST CDS_LIB pure_quanta
J 0
(-10300 7025);
DISPLAY INVISIBLE (-10300 7025);
FORCEPROP 1 LAST PATH I132
J 2
(-10250 7175);
DISPLAY 0.978723 (-10250 7175);
PAINT WHITE (-10250 7175);
DISPLAY INVISIBLE (-10250 7175);
FORCEPROP 1 LAST PART_NUMBER CS00002JB13
J 0
(-10400 7075);
DISPLAY 0.489362 (-10400 7075);
PAINT SKYBLUE (-10400 7075);
DISPLAY INVISIBLE (-10400 7075);
FORCEADD Q_RES..1
R 2
(-10300 7075);
FORCEPROP 1 LAST LOCATION R6010
J 2
(-10100 7075);
DISPLAY 0.489362 (-10100 7075);
PAINT SKYBLUE (-10100 7075);
FORCEPROP 0 LAST $SEC 1
J 0
(-10100 7100);
DISPLAY 0.680851 (-10100 7100);
PAINT MONO (-10100 7100);
DISPLAY INVISIBLE (-10100 7100);
FORCEPROP 0 LAST CDS_SEC 1
J 0
(-10100 7100);
DISPLAY 0.680851 (-10100 7100);
DISPLAY INVISIBLE (-10100 7100);
FORCEPROP 1 LASTPIN (-10200 7075) $PN 1
J 2
(-10212 7087);
DISPLAY 0.787234 (-10212 7087);
PAINT MONO (-10212 7087);
FORCEPROP 1 LASTPIN (-10400 7075) $PN 2
J 2
(-10362 7087);
DISPLAY 0.787234 (-10362 7087);
PAINT MONO (-10362 7087);
FORCEPROP 1 LAST VALUE 0
J 0
(-10450 7075);
DISPLAY 0.489362 (-10450 7075);
PAINT SKYBLUE (-10450 7075);
FORCEPROP 2 LAST CDS_LIB pure_quanta
J 0
(-10300 7075);
DISPLAY INVISIBLE (-10300 7075);
FORCEPROP 2 LAST BOM_COST MEM
J 0
(-10325 7225);
DISPLAY 0.744681 (-10325 7225);
PAINT WHITE (-10325 7225);
DISPLAY INVISIBLE (-10325 7225);
FORCEPROP 1 LAST WATTAGE 1/16W
J 0
(-10225 7000);
DISPLAY 0.489362 (-10225 7000);
PAINT SKYBLUE (-10225 7000);
DISPLAY INVISIBLE (-10225 7000);
FORCEPROP 1 LAST MATERIAL CHIP
J 0
(-10475 7050);
DISPLAY 0.489362 (-10475 7050);
PAINT SKYBLUE (-10475 7050);
DISPLAY INVISIBLE (-10475 7050);
FORCEPROP 1 LAST TOLERANCE 5%
J 2
(-10175 7050);
DISPLAY 0.489362 (-10175 7050);
PAINT SKYBLUE (-10175 7050);
DISPLAY INVISIBLE (-10175 7050);
FORCEPROP 1 LAST PACK_TYPE 0402LF
J 0
(-10475 7000);
DISPLAY 0.489362 (-10475 7000);
PAINT SKYBLUE (-10475 7000);
DISPLAY INVISIBLE (-10475 7000);
FORCEPROP 1 LAST PATH I133
J 2
(-10250 7225);
DISPLAY 0.978723 (-10250 7225);
PAINT WHITE (-10250 7225);
DISPLAY INVISIBLE (-10250 7225);
FORCEPROP 1 LAST PART_NUMBER CS00002JB13
J 0
(-10400 7125);
DISPLAY 0.489362 (-10400 7125);
PAINT SKYBLUE (-10400 7125);
DISPLAY INVISIBLE (-10400 7125);
FORCEADD Q_RES..1
R 2
(-10300 7125);
FORCEPROP 1 LAST LOCATION R6009
J 2
(-10100 7125);
DISPLAY 0.489362 (-10100 7125);
PAINT SKYBLUE (-10100 7125);
FORCEPROP 0 LAST $SEC 1
J 0
(-10100 7150);
DISPLAY 0.680851 (-10100 7150);
PAINT MONO (-10100 7150);
DISPLAY INVISIBLE (-10100 7150);
FORCEPROP 0 LAST CDS_SEC 1
J 0
(-10100 7150);
DISPLAY 0.680851 (-10100 7150);
DISPLAY INVISIBLE (-10100 7150);
FORCEPROP 1 LASTPIN (-10200 7125) $PN 1
J 2
(-10212 7137);
DISPLAY 0.787234 (-10212 7137);
PAINT MONO (-10212 7137);
FORCEPROP 1 LASTPIN (-10400 7125) $PN 2
J 2
(-10362 7137);
DISPLAY 0.787234 (-10362 7137);
PAINT MONO (-10362 7137);
FORCEPROP 1 LAST VALUE 0
J 0
(-10450 7125);
DISPLAY 0.489362 (-10450 7125);
PAINT SKYBLUE (-10450 7125);
FORCEPROP 2 LAST CDS_LIB pure_quanta
J 0
(-10300 7125);
DISPLAY INVISIBLE (-10300 7125);
FORCEPROP 2 LAST BOM_COST MEM
J 0
(-10325 7275);
DISPLAY 0.744681 (-10325 7275);
PAINT WHITE (-10325 7275);
DISPLAY INVISIBLE (-10325 7275);
FORCEPROP 1 LAST WATTAGE 1/16W
J 0
(-10225 7050);
DISPLAY 0.489362 (-10225 7050);
PAINT SKYBLUE (-10225 7050);
DISPLAY INVISIBLE (-10225 7050);
FORCEPROP 1 LAST MATERIAL CHIP
J 0
(-10475 7100);
DISPLAY 0.489362 (-10475 7100);
PAINT SKYBLUE (-10475 7100);
DISPLAY INVISIBLE (-10475 7100);
FORCEPROP 1 LAST TOLERANCE 5%
J 2
(-10175 7100);
DISPLAY 0.489362 (-10175 7100);
PAINT SKYBLUE (-10175 7100);
DISPLAY INVISIBLE (-10175 7100);
FORCEPROP 1 LAST PACK_TYPE 0402LF
J 0
(-10475 7050);
DISPLAY 0.489362 (-10475 7050);
PAINT SKYBLUE (-10475 7050);
DISPLAY INVISIBLE (-10475 7050);
FORCEPROP 1 LAST PATH I134
J 2
(-10250 7275);
DISPLAY 0.978723 (-10250 7275);
PAINT WHITE (-10250 7275);
DISPLAY INVISIBLE (-10250 7275);
FORCEPROP 1 LAST PART_NUMBER CS00002JB13
J 0
(-10400 7175);
DISPLAY 0.489362 (-10400 7175);
PAINT SKYBLUE (-10400 7175);
DISPLAY INVISIBLE (-10400 7175);
FORCEADD Q_RES..1
R 2
(-10300 7175);
FORCEPROP 1 LAST LOCATION R6008
J 2
(-10100 7175);
DISPLAY 0.489362 (-10100 7175);
PAINT SKYBLUE (-10100 7175);
FORCEPROP 0 LAST $SEC 1
J 0
(-10150 7225);
DISPLAY 0.680851 (-10150 7225);
PAINT MONO (-10150 7225);
DISPLAY INVISIBLE (-10150 7225);
FORCEPROP 0 LAST CDS_SEC 1
J 0
(-10150 7225);
DISPLAY 0.680851 (-10150 7225);
DISPLAY INVISIBLE (-10150 7225);
FORCEPROP 1 LASTPIN (-10200 7175) $PN 1
J 2
(-10212 7187);
DISPLAY 0.489362 (-10212 7187);
PAINT MONO (-10212 7187);
FORCEPROP 1 LASTPIN (-10400 7175) $PN 2
J 2
(-10362 7187);
DISPLAY 0.489362 (-10362 7187);
PAINT MONO (-10362 7187);
FORCEPROP 1 LAST VALUE 0
J 0
(-10450 7175);
DISPLAY 0.489362 (-10450 7175);
PAINT SKYBLUE (-10450 7175);
FORCEPROP 1 LAST PACK_TYPE 0402LF
J 0
(-10475 7100);
DISPLAY 0.489362 (-10475 7100);
PAINT SKYBLUE (-10475 7100);
DISPLAY INVISIBLE (-10475 7100);
FORCEPROP 1 LAST TOLERANCE 5%
J 2
(-10175 7150);
DISPLAY 0.489362 (-10175 7150);
PAINT SKYBLUE (-10175 7150);
DISPLAY INVISIBLE (-10175 7150);
FORCEPROP 1 LAST MATERIAL CHIP
J 0
(-10475 7150);
DISPLAY 0.489362 (-10475 7150);
PAINT SKYBLUE (-10475 7150);
DISPLAY INVISIBLE (-10475 7150);
FORCEPROP 1 LAST WATTAGE 1/16W
J 0
(-10225 7100);
DISPLAY 0.489362 (-10225 7100);
PAINT SKYBLUE (-10225 7100);
DISPLAY INVISIBLE (-10225 7100);
FORCEPROP 2 LAST BOM_COST MEM
J 0
(-10325 7325);
DISPLAY 0.744681 (-10325 7325);
PAINT WHITE (-10325 7325);
DISPLAY INVISIBLE (-10325 7325);
FORCEPROP 2 LAST CDS_LIB pure_quanta
J 0
(-10300 7175);
DISPLAY INVISIBLE (-10300 7175);
FORCEPROP 1 LAST PATH I135
J 2
(-10250 7325);
DISPLAY 0.978723 (-10250 7325);
PAINT WHITE (-10250 7325);
DISPLAY INVISIBLE (-10250 7325);
FORCEPROP 1 LAST PART_NUMBER CS00002JB13
J 0
(-10400 7225);
DISPLAY 0.489362 (-10400 7225);
PAINT SKYBLUE (-10400 7225);
DISPLAY INVISIBLE (-10400 7225);
FORCEADD OFFPAGE..4
(-10000 7475);
FORCEPROP 2 LAST $XR1 138 
J 0
(-9694 7475);
DISPLAY 0.638298 (-9694 7475);
PAINT MONO (-9694 7475);
FORCEPROP 2 LAST $XR0 132 
J 0
(-9814 7475);
DISPLAY 0.638298 (-9814 7475);
PAINT MONO (-9814 7475);
FORCEPROP 2 LAST CDS_LIB standard
J 0
(-10000 7475);
PAINT MONO (-10000 7475);
DISPLAY INVISIBLE (-10000 7475);
FORCEPROP 1 LAST OFFPAGE TRUE
J 0
(-9675 7350);
DISPLAY 0.872340 (-9675 7350);
PAINT GREEN (-9675 7350);
DISPLAY INVISIBLE (-9675 7350);
FORCEPROP 1 LAST COMMENT_BODY TRUE
J 0
(-10025 7375);
DISPLAY 0.872340 (-10025 7375);
PAINT PEACH (-10025 7375);
DISPLAY INVISIBLE (-10025 7375);
FORCEPROP 2 LAST PATH I136
J 0
(-9825 7550);
DISPLAY 0.680851 (-9825 7550);
DISPLAY INVISIBLE (-9825 7550);
FORCEADD OFFPAGE..2
(-10000 7725);
FORCEPROP 2 LAST $XR1 138 
J 0
(-9691 7725);
DISPLAY 0.638298 (-9691 7725);
PAINT MONO (-9691 7725);
FORCEPROP 2 LAST $XR0 132 
J 0
(-9811 7725);
DISPLAY 0.638298 (-9811 7725);
PAINT MONO (-9811 7725);
FORCEPROP 2 LAST CDS_LIB standard
J 0
(-10000 7725);
DISPLAY INVISIBLE (-10000 7725);
FORCEPROP 1 LAST OFFPAGE TRUE
J 0
(-9675 7600);
DISPLAY 0.872340 (-9675 7600);
PAINT GREEN (-9675 7600);
DISPLAY INVISIBLE (-9675 7600);
FORCEPROP 1 LAST COMMENT_BODY TRUE
J 0
(-10045 7630);
DISPLAY 0.872340 (-10045 7630);
PAINT PEACH (-10045 7630);
DISPLAY INVISIBLE (-10045 7630);
FORCEPROP 2 LAST PATH I137
J 0
(-9825 7800);
DISPLAY 0.680851 (-9825 7800);
DISPLAY INVISIBLE (-9825 7800);
FORCEADD OFFPAGE..2
(-10000 7675);
FORCEPROP 2 LAST $XR1 138 
J 0
(-9691 7675);
DISPLAY 0.638298 (-9691 7675);
PAINT MONO (-9691 7675);
FORCEPROP 2 LAST $XR0 132 
J 0
(-9811 7675);
DISPLAY 0.638298 (-9811 7675);
PAINT MONO (-9811 7675);
FORCEPROP 2 LAST CDS_LIB standard
J 0
(-10000 7675);
PAINT MONO (-10000 7675);
DISPLAY INVISIBLE (-10000 7675);
FORCEPROP 1 LAST OFFPAGE TRUE
J 0
(-9675 7550);
DISPLAY 0.872340 (-9675 7550);
PAINT GREEN (-9675 7550);
DISPLAY INVISIBLE (-9675 7550);
FORCEPROP 1 LAST COMMENT_BODY TRUE
J 0
(-10045 7580);
DISPLAY 0.872340 (-10045 7580);
PAINT PEACH (-10045 7580);
DISPLAY INVISIBLE (-10045 7580);
FORCEPROP 2 LAST PATH I138
J 0
(-9825 7750);
DISPLAY 0.680851 (-9825 7750);
DISPLAY INVISIBLE (-9825 7750);
FORCEADD OFFPAGE..2
(-10000 7575);
FORCEPROP 2 LAST $XR0 132 
J 0
(-9811 7575);
DISPLAY 0.638298 (-9811 7575);
PAINT MONO (-9811 7575);
FORCEPROP 2 LAST CDS_LIB standard
J 0
(-10000 7575);
PAINT MONO (-10000 7575);
DISPLAY INVISIBLE (-10000 7575);
FORCEPROP 1 LAST OFFPAGE TRUE
J 0
(-9675 7450);
DISPLAY 0.872340 (-9675 7450);
PAINT GREEN (-9675 7450);
DISPLAY INVISIBLE (-9675 7450);
FORCEPROP 1 LAST COMMENT_BODY TRUE
J 0
(-10045 7480);
DISPLAY 0.872340 (-10045 7480);
PAINT PEACH (-10045 7480);
DISPLAY INVISIBLE (-10045 7480);
FORCEPROP 2 LAST PATH I139
J 0
(-9825 7650);
DISPLAY 0.680851 (-9825 7650);
DISPLAY INVISIBLE (-9825 7650);
FORCEADD OFFPAGE..6
(-16200 6675);
FORCEPROP 2 LAST $XR0 151 
J 0
(-16480 6675);
DISPLAY 0.638298 (-16480 6675);
PAINT MONO (-16480 6675);
FORCEPROP 2 LAST $XR1 249 
J 0
(-16600 6675);
DISPLAY 0.638298 (-16600 6675);
PAINT MONO (-16600 6675);
FORCEPROP 2 LAST CDS_LIB standard
J 0
(-16200 6675);
DISPLAY INVISIBLE (-16200 6675);
FORCEPROP 1 LAST OFFPAGE TRUE
J 0
(-15875 6550);
DISPLAY 0.872340 (-15875 6550);
PAINT GREEN (-15875 6550);
DISPLAY INVISIBLE (-15875 6550);
FORCEPROP 1 LAST COMMENT_BODY TRUE
J 0
(-16100 6600);
DISPLAY 0.872340 (-16100 6600);
PAINT PEACH (-16100 6600);
DISPLAY INVISIBLE (-16100 6600);
FORCEPROP 2 LAST PATH I14
J 0
(-16150 6750);
DISPLAY 0.680851 (-16150 6750);
DISPLAY INVISIBLE (-16150 6750);
FORCEADD OFFPAGE..2
(-10000 7625);
FORCEPROP 2 LAST $XR1 138 
J 0
(-9691 7625);
DISPLAY 0.638298 (-9691 7625);
PAINT MONO (-9691 7625);
FORCEPROP 2 LAST $XR0 132 
J 0
(-9811 7625);
DISPLAY 0.638298 (-9811 7625);
PAINT MONO (-9811 7625);
FORCEPROP 2 LAST CDS_LIB standard
J 0
(-10000 7625);
PAINT MONO (-10000 7625);
DISPLAY INVISIBLE (-10000 7625);
FORCEPROP 1 LAST OFFPAGE TRUE
J 0
(-9675 7500);
DISPLAY 0.872340 (-9675 7500);
PAINT GREEN (-9675 7500);
DISPLAY INVISIBLE (-9675 7500);
FORCEPROP 1 LAST COMMENT_BODY TRUE
J 0
(-10045 7530);
DISPLAY 0.872340 (-10045 7530);
PAINT PEACH (-10045 7530);
DISPLAY INVISIBLE (-10045 7530);
FORCEPROP 2 LAST PATH I140
J 0
(-9825 7700);
DISPLAY 0.680851 (-9825 7700);
DISPLAY INVISIBLE (-9825 7700);
FORCEADD OFFPAGE..4
(-10000 7525);
FORCEPROP 2 LAST $XR1 138 
J 0
(-9694 7525);
DISPLAY 0.638298 (-9694 7525);
PAINT MONO (-9694 7525);
FORCEPROP 2 LAST $XR0 132 
J 0
(-9814 7525);
DISPLAY 0.638298 (-9814 7525);
PAINT MONO (-9814 7525);
FORCEPROP 2 LAST CDS_LIB standard
J 0
(-10000 7525);
PAINT MONO (-10000 7525);
DISPLAY INVISIBLE (-10000 7525);
FORCEPROP 1 LAST OFFPAGE TRUE
J 0
(-9675 7400);
DISPLAY 0.872340 (-9675 7400);
PAINT GREEN (-9675 7400);
DISPLAY INVISIBLE (-9675 7400);
FORCEPROP 1 LAST COMMENT_BODY TRUE
J 0
(-10025 7425);
DISPLAY 0.872340 (-10025 7425);
PAINT PEACH (-10025 7425);
DISPLAY INVISIBLE (-10025 7425);
FORCEPROP 2 LAST PATH I141
J 0
(-9825 7600);
DISPLAY 0.680851 (-9825 7600);
DISPLAY INVISIBLE (-9825 7600);
FORCEADD OFFPAGE..4
(-10000 7775);
FORCEPROP 2 LAST $XR1 138 
J 0
(-9694 7775);
DISPLAY 0.638298 (-9694 7775);
PAINT MONO (-9694 7775);
FORCEPROP 2 LAST $XR0 132 
J 0
(-9814 7775);
DISPLAY 0.638298 (-9814 7775);
PAINT MONO (-9814 7775);
FORCEPROP 2 LAST CDS_LIB standard
J 0
(-10000 7775);
DISPLAY INVISIBLE (-10000 7775);
FORCEPROP 1 LAST OFFPAGE TRUE
J 0
(-9675 7650);
DISPLAY 0.872340 (-9675 7650);
PAINT GREEN (-9675 7650);
DISPLAY INVISIBLE (-9675 7650);
FORCEPROP 1 LAST COMMENT_BODY TRUE
J 0
(-10025 7675);
DISPLAY 0.872340 (-10025 7675);
PAINT PEACH (-10025 7675);
DISPLAY INVISIBLE (-10025 7675);
FORCEPROP 2 LAST PATH I142
J 0
(-9825 7850);
DISPLAY 0.680851 (-9825 7850);
DISPLAY INVISIBLE (-9825 7850);
FORCEADD OFFPAGE..2
(-9375 6775);
FORCEPROP 2 LAST $XR0 151 
J 0
(-9186 6775);
DISPLAY 0.638298 (-9186 6775);
PAINT MONO (-9186 6775);
FORCEPROP 2 LAST $XR1 80 
J 0
(-9066 6775);
DISPLAY 0.638298 (-9066 6775);
PAINT MONO (-9066 6775);
FORCEPROP 2 LAST CDS_LIB standard
J 0
(-9375 6775);
PAINT MONO (-9375 6775);
DISPLAY INVISIBLE (-9375 6775);
FORCEPROP 1 LAST OFFPAGE TRUE
J 0
(-9050 6650);
DISPLAY 0.872340 (-9050 6650);
PAINT GREEN (-9050 6650);
DISPLAY INVISIBLE (-9050 6650);
FORCEPROP 1 LAST COMMENT_BODY TRUE
J 0
(-9420 6680);
DISPLAY 0.872340 (-9420 6680);
PAINT PEACH (-9420 6680);
DISPLAY INVISIBLE (-9420 6680);
FORCEPROP 2 LAST PATH I143
J 0
(-9200 6850);
DISPLAY 0.680851 (-9200 6850);
DISPLAY INVISIBLE (-9200 6850);
FORCEADD OFFPAGE..4
(-9375 6825);
FORCEPROP 2 LAST $XR0 80 
J 0
(-9189 6825);
DISPLAY 0.638298 (-9189 6825);
PAINT MONO (-9189 6825);
FORCEPROP 2 LAST $XR1 151 
J 0
(-9099 6825);
DISPLAY 0.638298 (-9099 6825);
PAINT MONO (-9099 6825);
FORCEPROP 2 LAST CDS_LIB standard
J 0
(-9375 6825);
PAINT MONO (-9375 6825);
DISPLAY INVISIBLE (-9375 6825);
FORCEPROP 1 LAST OFFPAGE TRUE
J 0
(-9050 6700);
DISPLAY 0.872340 (-9050 6700);
PAINT GREEN (-9050 6700);
DISPLAY INVISIBLE (-9050 6700);
FORCEPROP 1 LAST COMMENT_BODY TRUE
J 0
(-9400 6725);
DISPLAY 0.872340 (-9400 6725);
PAINT PEACH (-9400 6725);
DISPLAY INVISIBLE (-9400 6725);
FORCEPROP 2 LAST PATH I144
J 0
(-9200 6900);
DISPLAY 0.680851 (-9200 6900);
DISPLAY INVISIBLE (-9200 6900);
FORCEADD OFFPAGE..2
(-9375 6875);
FORCEPROP 2 LAST $XR0 151 
J 0
(-9186 6875);
DISPLAY 0.638298 (-9186 6875);
PAINT MONO (-9186 6875);
FORCEPROP 2 LAST $XR1 80 
J 0
(-9066 6875);
DISPLAY 0.638298 (-9066 6875);
PAINT MONO (-9066 6875);
FORCEPROP 2 LAST CDS_LIB standard
J 0
(-9375 6875);
DISPLAY INVISIBLE (-9375 6875);
FORCEPROP 1 LAST OFFPAGE TRUE
J 0
(-9050 6750);
DISPLAY 0.872340 (-9050 6750);
PAINT GREEN (-9050 6750);
DISPLAY INVISIBLE (-9050 6750);
FORCEPROP 1 LAST COMMENT_BODY TRUE
J 0
(-9420 6780);
DISPLAY 0.872340 (-9420 6780);
PAINT PEACH (-9420 6780);
DISPLAY INVISIBLE (-9420 6780);
FORCEPROP 2 LAST PATH I145
J 0
(-9200 6950);
DISPLAY 0.680851 (-9200 6950);
DISPLAY INVISIBLE (-9200 6950);
FORCEADD OFFPAGE..2
(-9375 6925);
FORCEPROP 2 LAST $XR1 80 
J 0
(-9066 6925);
DISPLAY 0.638298 (-9066 6925);
PAINT MONO (-9066 6925);
FORCEPROP 2 LAST $XR0 151 
J 0
(-9186 6925);
DISPLAY 0.638298 (-9186 6925);
PAINT MONO (-9186 6925);
FORCEPROP 2 LAST CDS_LIB standard
J 0
(-9375 6925);
PAINT MONO (-9375 6925);
DISPLAY INVISIBLE (-9375 6925);
FORCEPROP 1 LAST OFFPAGE TRUE
J 0
(-9050 6800);
DISPLAY 0.872340 (-9050 6800);
PAINT GREEN (-9050 6800);
DISPLAY INVISIBLE (-9050 6800);
FORCEPROP 1 LAST COMMENT_BODY TRUE
J 0
(-9420 6830);
DISPLAY 0.872340 (-9420 6830);
PAINT PEACH (-9420 6830);
DISPLAY INVISIBLE (-9420 6830);
FORCEPROP 2 LAST PATH I146
J 0
(-9200 7000);
DISPLAY 0.680851 (-9200 7000);
DISPLAY INVISIBLE (-9200 7000);
FORCEADD OFFPAGE..4
(-9375 7075);
FORCEPROP 2 LAST $XR1 151 
J 0
(-9099 7075);
DISPLAY 0.638298 (-9099 7075);
PAINT MONO (-9099 7075);
FORCEPROP 2 LAST $XR0 80 
J 0
(-9189 7075);
DISPLAY 0.638298 (-9189 7075);
PAINT MONO (-9189 7075);
FORCEPROP 2 LAST CDS_LIB standard
J 0
(-9375 7075);
PAINT MONO (-9375 7075);
DISPLAY INVISIBLE (-9375 7075);
FORCEPROP 1 LAST OFFPAGE TRUE
J 0
(-9050 6950);
DISPLAY 0.872340 (-9050 6950);
PAINT GREEN (-9050 6950);
DISPLAY INVISIBLE (-9050 6950);
FORCEPROP 1 LAST COMMENT_BODY TRUE
J 0
(-9400 6975);
DISPLAY 0.872340 (-9400 6975);
PAINT PEACH (-9400 6975);
DISPLAY INVISIBLE (-9400 6975);
FORCEPROP 2 LAST PATH I147
J 0
(-9200 7150);
DISPLAY 0.680851 (-9200 7150);
DISPLAY INVISIBLE (-9200 7150);
FORCEADD OFFPAGE..2
(-9375 7025);
FORCEPROP 2 LAST $XR1 80 
J 0
(-9066 7025);
DISPLAY 0.638298 (-9066 7025);
PAINT MONO (-9066 7025);
FORCEPROP 2 LAST $XR0 151 
J 0
(-9186 7025);
DISPLAY 0.638298 (-9186 7025);
PAINT MONO (-9186 7025);
FORCEPROP 2 LAST CDS_LIB standard
J 0
(-9375 7025);
PAINT MONO (-9375 7025);
DISPLAY INVISIBLE (-9375 7025);
FORCEPROP 1 LAST OFFPAGE TRUE
J 0
(-9050 6900);
DISPLAY 0.872340 (-9050 6900);
PAINT GREEN (-9050 6900);
DISPLAY INVISIBLE (-9050 6900);
FORCEPROP 1 LAST COMMENT_BODY TRUE
J 0
(-9420 6930);
DISPLAY 0.872340 (-9420 6930);
PAINT PEACH (-9420 6930);
DISPLAY INVISIBLE (-9420 6930);
FORCEPROP 2 LAST PATH I148
J 0
(-9200 7100);
DISPLAY 0.680851 (-9200 7100);
DISPLAY INVISIBLE (-9200 7100);
FORCEADD OFFPAGE..2
(-9375 7125);
FORCEPROP 2 LAST $XR0 151 
J 0
(-9186 7125);
DISPLAY 0.638298 (-9186 7125);
PAINT MONO (-9186 7125);
FORCEPROP 2 LAST $XR1 80 
J 0
(-9066 7125);
DISPLAY 0.638298 (-9066 7125);
PAINT MONO (-9066 7125);
FORCEPROP 2 LAST CDS_LIB standard
J 0
(-9375 7125);
PAINT MONO (-9375 7125);
DISPLAY INVISIBLE (-9375 7125);
FORCEPROP 1 LAST OFFPAGE TRUE
J 0
(-9050 7000);
DISPLAY 0.872340 (-9050 7000);
PAINT GREEN (-9050 7000);
DISPLAY INVISIBLE (-9050 7000);
FORCEPROP 1 LAST COMMENT_BODY TRUE
J 0
(-9420 7030);
DISPLAY 0.872340 (-9420 7030);
PAINT PEACH (-9420 7030);
DISPLAY INVISIBLE (-9420 7030);
FORCEPROP 2 LAST PATH I149
J 0
(-9200 7200);
DISPLAY 0.680851 (-9200 7200);
DISPLAY INVISIBLE (-9200 7200);
FORCEADD OFFPAGE..2
(-9375 7175);
FORCEPROP 2 LAST $XR0 151 
J 0
(-9186 7175);
DISPLAY 0.638298 (-9186 7175);
PAINT MONO (-9186 7175);
FORCEPROP 2 LAST $XR1 80 
J 0
(-9066 7175);
DISPLAY 0.638298 (-9066 7175);
PAINT MONO (-9066 7175);
FORCEPROP 2 LAST CDS_LIB standard
J 0
(-9375 7175);
PAINT MONO (-9375 7175);
DISPLAY INVISIBLE (-9375 7175);
FORCEPROP 1 LAST OFFPAGE TRUE
J 0
(-9050 7050);
DISPLAY 0.872340 (-9050 7050);
PAINT GREEN (-9050 7050);
DISPLAY INVISIBLE (-9050 7050);
FORCEPROP 1 LAST COMMENT_BODY TRUE
J 0
(-9420 7080);
DISPLAY 0.872340 (-9420 7080);
PAINT PEACH (-9420 7080);
DISPLAY INVISIBLE (-9420 7080);
FORCEPROP 2 LAST PATH I150
J 0
(-9200 7250);
DISPLAY 0.680851 (-9200 7250);
DISPLAY INVISIBLE (-9200 7250);
FORCEADD OFFPAGE..4
(-10000 7975);
FORCEPROP 2 LAST $XR0 77 
J 0
(-9814 7975);
DISPLAY 0.638298 (-9814 7975);
PAINT MONO (-9814 7975);
FORCEPROP 2 LAST CDS_LIB standard
J 0
(-10000 7975);
PAINT MONO (-10000 7975);
DISPLAY INVISIBLE (-10000 7975);
FORCEPROP 1 LAST OFFPAGE TRUE
J 0
(-9675 7850);
DISPLAY 0.872340 (-9675 7850);
PAINT GREEN (-9675 7850);
DISPLAY INVISIBLE (-9675 7850);
FORCEPROP 1 LAST COMMENT_BODY TRUE
J 0
(-10025 7875);
DISPLAY 0.872340 (-10025 7875);
PAINT PEACH (-10025 7875);
DISPLAY INVISIBLE (-10025 7875);
FORCEPROP 2 LAST PATH I151
J 0
(-9825 8050);
DISPLAY 0.680851 (-9825 8050);
DISPLAY INVISIBLE (-9825 8050);
FORCEADD OFFPAGE..4
(-10000 7925);
FORCEPROP 2 LAST $XR0 77 
J 0
(-9814 7925);
DISPLAY 0.638298 (-9814 7925);
PAINT MONO (-9814 7925);
FORCEPROP 2 LAST CDS_LIB standard
J 0
(-10000 7925);
PAINT MONO (-10000 7925);
DISPLAY INVISIBLE (-10000 7925);
FORCEPROP 1 LAST OFFPAGE TRUE
J 0
(-9675 7800);
DISPLAY 0.872340 (-9675 7800);
PAINT GREEN (-9675 7800);
DISPLAY INVISIBLE (-9675 7800);
FORCEPROP 1 LAST COMMENT_BODY TRUE
J 0
(-10025 7825);
DISPLAY 0.872340 (-10025 7825);
PAINT PEACH (-10025 7825);
DISPLAY INVISIBLE (-10025 7825);
FORCEPROP 2 LAST PATH I152
J 0
(-9825 8000);
DISPLAY 0.680851 (-9825 8000);
DISPLAY INVISIBLE (-9825 8000);
FORCEADD OFFPAGE..4
(-10000 7825);
FORCEPROP 2 LAST $XR0 133 
J 0
(-9814 7825);
DISPLAY 0.638298 (-9814 7825);
PAINT MONO (-9814 7825);
FORCEPROP 2 LAST CDS_LIB standard
J 0
(-10000 7825);
PAINT MONO (-10000 7825);
DISPLAY INVISIBLE (-10000 7825);
FORCEPROP 1 LAST OFFPAGE TRUE
J 0
(-9675 7700);
DISPLAY 0.872340 (-9675 7700);
PAINT GREEN (-9675 7700);
DISPLAY INVISIBLE (-9675 7700);
FORCEPROP 1 LAST COMMENT_BODY TRUE
J 0
(-10025 7725);
DISPLAY 0.872340 (-10025 7725);
PAINT PEACH (-10025 7725);
DISPLAY INVISIBLE (-10025 7725);
FORCEPROP 2 LAST PATH I153
J 0
(-9825 7900);
DISPLAY 0.680851 (-9825 7900);
DISPLAY INVISIBLE (-9825 7900);
FORCEADD OFFPAGE..4
(-10000 8025);
FORCEPROP 2 LAST $XR0 77 
J 0
(-9814 8025);
DISPLAY 0.638298 (-9814 8025);
PAINT MONO (-9814 8025);
FORCEPROP 2 LAST CDS_LIB standard
J 0
(-10000 8025);
PAINT MONO (-10000 8025);
DISPLAY INVISIBLE (-10000 8025);
FORCEPROP 1 LAST OFFPAGE TRUE
J 0
(-9675 7900);
DISPLAY 0.872340 (-9675 7900);
PAINT GREEN (-9675 7900);
DISPLAY INVISIBLE (-9675 7900);
FORCEPROP 1 LAST COMMENT_BODY TRUE
J 0
(-10025 7925);
DISPLAY 0.872340 (-10025 7925);
PAINT PEACH (-10025 7925);
DISPLAY INVISIBLE (-10025 7925);
FORCEPROP 2 LAST PATH I154
J 0
(-9825 8100);
DISPLAY 0.680851 (-9825 8100);
DISPLAY INVISIBLE (-9825 8100);
FORCEADD OFFPAGE..4
(-10000 8125);
FORCEPROP 2 LAST $XR0 77 
J 0
(-9814 8125);
DISPLAY 0.638298 (-9814 8125);
PAINT MONO (-9814 8125);
FORCEPROP 2 LAST CDS_LIB standard
J 0
(-10000 8125);
PAINT MONO (-10000 8125);
DISPLAY INVISIBLE (-10000 8125);
FORCEPROP 1 LAST OFFPAGE TRUE
J 0
(-9675 8000);
DISPLAY 0.872340 (-9675 8000);
PAINT GREEN (-9675 8000);
DISPLAY INVISIBLE (-9675 8000);
FORCEPROP 1 LAST COMMENT_BODY TRUE
J 0
(-10025 8025);
DISPLAY 0.872340 (-10025 8025);
PAINT PEACH (-10025 8025);
DISPLAY INVISIBLE (-10025 8025);
FORCEPROP 2 LAST PATH I155
J 0
(-9825 8200);
DISPLAY 0.680851 (-9825 8200);
DISPLAY INVISIBLE (-9825 8200);
FORCEADD OFFPAGE..4
(-10000 8175);
FORCEPROP 2 LAST $XR0 77 
J 0
(-9814 8175);
DISPLAY 0.638298 (-9814 8175);
PAINT MONO (-9814 8175);
FORCEPROP 2 LAST CDS_LIB standard
J 0
(-10000 8175);
PAINT MONO (-10000 8175);
DISPLAY INVISIBLE (-10000 8175);
FORCEPROP 1 LAST OFFPAGE TRUE
J 0
(-9675 8050);
DISPLAY 0.872340 (-9675 8050);
PAINT GREEN (-9675 8050);
DISPLAY INVISIBLE (-9675 8050);
FORCEPROP 1 LAST COMMENT_BODY TRUE
J 0
(-10025 8075);
DISPLAY 0.872340 (-10025 8075);
PAINT PEACH (-10025 8075);
DISPLAY INVISIBLE (-10025 8075);
FORCEPROP 2 LAST PATH I156
J 0
(-9825 8250);
DISPLAY 0.680851 (-9825 8250);
DISPLAY INVISIBLE (-9825 8250);
FORCEADD OFFPAGE..4
(-10000 8075);
FORCEPROP 2 LAST $XR0 77 
J 0
(-9814 8075);
DISPLAY 0.638298 (-9814 8075);
PAINT MONO (-9814 8075);
FORCEPROP 2 LAST CDS_LIB standard
J 0
(-10000 8075);
PAINT MONO (-10000 8075);
DISPLAY INVISIBLE (-10000 8075);
FORCEPROP 1 LAST OFFPAGE TRUE
J 0
(-9675 7950);
DISPLAY 0.872340 (-9675 7950);
PAINT GREEN (-9675 7950);
DISPLAY INVISIBLE (-9675 7950);
FORCEPROP 1 LAST COMMENT_BODY TRUE
J 0
(-10025 7975);
DISPLAY 0.872340 (-10025 7975);
PAINT PEACH (-10025 7975);
DISPLAY INVISIBLE (-10025 7975);
FORCEPROP 2 LAST PATH I157
J 0
(-9825 8150);
DISPLAY 0.680851 (-9825 8150);
DISPLAY INVISIBLE (-9825 8150);
FORCEADD OFFPAGE..3
(-10000 8475);
FORCEPROP 2 LAST $XR1 81 
J 0
(-9696 8475);
DISPLAY 0.638298 (-9696 8475);
PAINT MONO (-9696 8475);
FORCEPROP 2 LAST $XR0 29 
J 0
(-9786 8475);
DISPLAY 0.638298 (-9786 8475);
PAINT MONO (-9786 8475);
FORCEPROP 2 LAST CDS_LIB standard
J 0
(-10000 8475);
DISPLAY INVISIBLE (-10000 8475);
FORCEPROP 1 LAST OFFPAGE TRUE
J 0
(-9675 8350);
DISPLAY 0.872340 (-9675 8350);
PAINT GREEN (-9675 8350);
DISPLAY INVISIBLE (-9675 8350);
FORCEPROP 1 LAST COMMENT_BODY TRUE
J 0
(-10050 8375);
DISPLAY 0.872340 (-10050 8375);
PAINT PEACH (-10050 8375);
DISPLAY INVISIBLE (-10050 8375);
FORCEPROP 2 LAST PATH I158
J 0
(-9800 8550);
DISPLAY 0.680851 (-9800 8550);
DISPLAY INVISIBLE (-9800 8550);
FORCEADD OFFPAGE..3
(-10000 8425);
FORCEPROP 2 LAST $XR1 81 
J 0
(-9696 8425);
DISPLAY 0.638298 (-9696 8425);
PAINT MONO (-9696 8425);
FORCEPROP 2 LAST $XR0 29 
J 0
(-9786 8425);
DISPLAY 0.638298 (-9786 8425);
PAINT MONO (-9786 8425);
FORCEPROP 2 LAST CDS_LIB standard
J 0
(-10000 8425);
DISPLAY INVISIBLE (-10000 8425);
FORCEPROP 1 LAST OFFPAGE TRUE
J 0
(-9675 8300);
DISPLAY 0.872340 (-9675 8300);
PAINT GREEN (-9675 8300);
DISPLAY INVISIBLE (-9675 8300);
FORCEPROP 1 LAST COMMENT_BODY TRUE
J 0
(-10050 8325);
DISPLAY 0.872340 (-10050 8325);
PAINT PEACH (-10050 8325);
DISPLAY INVISIBLE (-10050 8325);
FORCEPROP 2 LAST PATH I159
J 0
(-9800 8500);
DISPLAY 0.680851 (-9800 8500);
DISPLAY INVISIBLE (-9800 8500);
FORCEADD UNIVERSAL_GND..1
(-15200 3950);
FORCEPROP 3 LASTPIN (-15200 4000) SIG_NAME GND\g
J 0
(-15190 4010);
DISPLAY 0.659574 (-15190 4010);
PAINT MONO (-15190 4010);
DISPLAY INVISIBLE (-15190 4010);
FORCEPROP 2 LAST CDS_LIB pure_quanta_power
J 0
(-15200 3950);
DISPLAY INVISIBLE (-15200 3950);
FORCEPROP 1 LAST HDL_POWER GND
J 1
(-15175 3875);
DISPLAY 0.702128 (-15175 3875);
PAINT GREEN (-15175 3875);
DISPLAY INVISIBLE (-15175 3875);
FORCEPROP 1 LAST PATH I16
J 0
(-15125 3950);
DISPLAY 0.872340 (-15125 3950);
PAINT AQUA (-15125 3950);
DISPLAY INVISIBLE (-15125 3950);
FORCEADD OFFPAGE..3
(-10000 8375);
FORCEPROP 2 LAST $XR1 81 
J 0
(-9696 8375);
DISPLAY 0.638298 (-9696 8375);
PAINT MONO (-9696 8375);
FORCEPROP 2 LAST $XR0 29 
J 0
(-9786 8375);
DISPLAY 0.638298 (-9786 8375);
PAINT MONO (-9786 8375);
FORCEPROP 2 LAST CDS_LIB standard
J 0
(-10000 8375);
DISPLAY INVISIBLE (-10000 8375);
FORCEPROP 1 LAST OFFPAGE TRUE
J 0
(-9675 8250);
DISPLAY 0.872340 (-9675 8250);
PAINT GREEN (-9675 8250);
DISPLAY INVISIBLE (-9675 8250);
FORCEPROP 1 LAST COMMENT_BODY TRUE
J 0
(-10050 8275);
DISPLAY 0.872340 (-10050 8275);
PAINT PEACH (-10050 8275);
DISPLAY INVISIBLE (-10050 8275);
FORCEPROP 2 LAST PATH I160
J 0
(-9800 8450);
DISPLAY 0.680851 (-9800 8450);
DISPLAY INVISIBLE (-9800 8450);
FORCEADD OFFPAGE..3
(-10000 8325);
FORCEPROP 2 LAST $XR1 81 
J 0
(-9696 8325);
DISPLAY 0.638298 (-9696 8325);
PAINT MONO (-9696 8325);
FORCEPROP 2 LAST $XR0 29 
J 0
(-9786 8325);
DISPLAY 0.638298 (-9786 8325);
PAINT MONO (-9786 8325);
FORCEPROP 2 LAST CDS_LIB standard
J 0
(-10000 8325);
DISPLAY INVISIBLE (-10000 8325);
FORCEPROP 1 LAST OFFPAGE TRUE
J 0
(-9675 8200);
DISPLAY 0.872340 (-9675 8200);
PAINT GREEN (-9675 8200);
DISPLAY INVISIBLE (-9675 8200);
FORCEPROP 1 LAST COMMENT_BODY TRUE
J 0
(-10050 8225);
DISPLAY 0.872340 (-10050 8225);
PAINT PEACH (-10050 8225);
DISPLAY INVISIBLE (-10050 8225);
FORCEPROP 2 LAST PATH I161
J 0
(-9800 8400);
DISPLAY 0.680851 (-9800 8400);
DISPLAY INVISIBLE (-9800 8400);
FORCEADD OFFPAGE..4
(-10000 8525);
FORCEPROP 2 LAST $XR1 81 
J 0
(-9724 8525);
DISPLAY 0.638298 (-9724 8525);
PAINT MONO (-9724 8525);
FORCEPROP 2 LAST $XR0 29 
J 0
(-9814 8525);
DISPLAY 0.638298 (-9814 8525);
PAINT MONO (-9814 8525);
FORCEPROP 2 LAST CDS_LIB standard
J 0
(-10000 8525);
PAINT MONO (-10000 8525);
DISPLAY INVISIBLE (-10000 8525);
FORCEPROP 1 LAST OFFPAGE TRUE
J 0
(-9675 8400);
DISPLAY 0.872340 (-9675 8400);
PAINT GREEN (-9675 8400);
DISPLAY INVISIBLE (-9675 8400);
FORCEPROP 1 LAST COMMENT_BODY TRUE
J 0
(-10025 8425);
DISPLAY 0.872340 (-10025 8425);
PAINT PEACH (-10025 8425);
DISPLAY INVISIBLE (-10025 8425);
FORCEPROP 2 LAST PATH I162
J 0
(-9825 8600);
DISPLAY 0.680851 (-9825 8600);
DISPLAY INVISIBLE (-9825 8600);
FORCEADD OFFPAGE..4
(-10000 8625);
FORCEPROP 2 LAST $XR1 81 
J 0
(-9724 8625);
DISPLAY 0.638298 (-9724 8625);
PAINT MONO (-9724 8625);
FORCEPROP 2 LAST $XR0 29 
J 0
(-9814 8625);
DISPLAY 0.638298 (-9814 8625);
PAINT MONO (-9814 8625);
FORCEPROP 2 LAST CDS_LIB standard
J 0
(-10000 8625);
PAINT MONO (-10000 8625);
DISPLAY INVISIBLE (-10000 8625);
FORCEPROP 1 LAST OFFPAGE TRUE
J 0
(-9675 8500);
DISPLAY 0.872340 (-9675 8500);
DISPLAY INVISIBLE (-9675 8500);
FORCEPROP 1 LAST COMMENT_BODY TRUE
J 0
(-10025 8525);
DISPLAY 0.872340 (-10025 8525);
PAINT GREEN (-10025 8525);
DISPLAY INVISIBLE (-10025 8525);
FORCEPROP 2 LAST PATH I163
J 0
(-9825 8700);
DISPLAY 0.680851 (-9825 8700);
DISPLAY INVISIBLE (-9825 8700);
FORCEADD OFFPAGE..4
(-10000 8675);
FORCEPROP 2 LAST $XR2 81 
J 0
(-9634 8675);
DISPLAY 0.638298 (-9634 8675);
PAINT MONO (-9634 8675);
FORCEPROP 2 LAST $XR1 76 
J 0
(-9724 8675);
DISPLAY 0.638298 (-9724 8675);
PAINT MONO (-9724 8675);
FORCEPROP 2 LAST $XR0 29 
J 0
(-9814 8675);
DISPLAY 0.638298 (-9814 8675);
PAINT MONO (-9814 8675);
FORCEPROP 2 LAST CDS_LIB standard
J 0
(-10000 8675);
DISPLAY INVISIBLE (-10000 8675);
FORCEPROP 1 LAST OFFPAGE TRUE
J 0
(-9675 8550);
DISPLAY 0.872340 (-9675 8550);
PAINT GREEN (-9675 8550);
DISPLAY INVISIBLE (-9675 8550);
FORCEPROP 1 LAST COMMENT_BODY TRUE
J 0
(-10025 8575);
DISPLAY 0.872340 (-10025 8575);
PAINT PEACH (-10025 8575);
DISPLAY INVISIBLE (-10025 8575);
FORCEPROP 2 LAST PATH I164
J 0
(-9825 8750);
DISPLAY 0.680851 (-9825 8750);
DISPLAY INVISIBLE (-9825 8750);
FORCEADD OFFPAGE..4
(-10000 8925);
FORCEPROP 2 LAST $XR0 77 
J 0
(-9814 8925);
DISPLAY 0.638298 (-9814 8925);
PAINT MONO (-9814 8925);
FORCEPROP 2 LAST CDS_LIB standard
J 0
(-10000 8925);
PAINT MONO (-10000 8925);
DISPLAY INVISIBLE (-10000 8925);
FORCEPROP 1 LAST OFFPAGE TRUE
J 0
(-9675 8800);
DISPLAY 0.872340 (-9675 8800);
PAINT GREEN (-9675 8800);
DISPLAY INVISIBLE (-9675 8800);
FORCEPROP 1 LAST COMMENT_BODY TRUE
J 0
(-10025 8825);
DISPLAY 0.872340 (-10025 8825);
PAINT PEACH (-10025 8825);
DISPLAY INVISIBLE (-10025 8825);
FORCEPROP 2 LAST PATH I166
J 0
(-9825 9000);
DISPLAY 0.680851 (-9825 9000);
DISPLAY INVISIBLE (-9825 9000);
FORCEADD OFFPAGE..2
(-10000 9275);
FORCEPROP 2 LAST $XR0 116 
J 0
(-9811 9275);
DISPLAY 0.638298 (-9811 9275);
PAINT MONO (-9811 9275);
FORCEPROP 2 LAST CDS_LIB standard
J 0
(-10000 9275);
DISPLAY INVISIBLE (-10000 9275);
FORCEPROP 1 LAST OFFPAGE TRUE
J 0
(-9675 9150);
DISPLAY 0.872340 (-9675 9150);
PAINT GREEN (-9675 9150);
DISPLAY INVISIBLE (-9675 9150);
FORCEPROP 1 LAST COMMENT_BODY TRUE
J 0
(-10045 9180);
DISPLAY 0.872340 (-10045 9180);
PAINT PEACH (-10045 9180);
DISPLAY INVISIBLE (-10045 9180);
FORCEPROP 2 LAST PATH I167
J 0
(-9825 9350);
DISPLAY 0.680851 (-9825 9350);
DISPLAY INVISIBLE (-9825 9350);
FORCEADD OFFPAGE..4
(-10000 9225);
FORCEPROP 2 LAST $XR0 130 
J 0
(-9814 9225);
DISPLAY 0.638298 (-9814 9225);
PAINT MONO (-9814 9225);
FORCEPROP 2 LAST CDS_LIB standard
J 0
(-10000 9225);
DISPLAY INVISIBLE (-10000 9225);
FORCEPROP 1 LAST OFFPAGE TRUE
J 0
(-9675 9100);
DISPLAY 0.872340 (-9675 9100);
PAINT GREEN (-9675 9100);
DISPLAY INVISIBLE (-9675 9100);
FORCEPROP 1 LAST COMMENT_BODY TRUE
J 0
(-10025 9125);
DISPLAY 0.872340 (-10025 9125);
PAINT PEACH (-10025 9125);
DISPLAY INVISIBLE (-10025 9125);
FORCEPROP 2 LAST PATH I168
J 0
(-9825 9300);
DISPLAY 0.680851 (-9825 9300);
DISPLAY INVISIBLE (-9825 9300);
FORCEADD Q_RES..1
(-9450 8825);
FORCEPROP 1 LAST LOCATION R3778
J 0
(-9650 8825);
DISPLAY 0.638298 (-9650 8825);
FORCEPROP 0 LAST $SEC 1
J 0
(-9200 8875);
DISPLAY 0.680851 (-9200 8875);
PAINT MONO (-9200 8875);
DISPLAY INVISIBLE (-9200 8875);
FORCEPROP 0 LAST CDS_SEC 1
J 0
(-9200 8875);
DISPLAY 1.021277 (-9200 8875);
DISPLAY INVISIBLE (-9200 8875);
FORCEPROP 1 LASTPIN (-9550 8825) $PN 1
J 0
(-9538 8837);
DISPLAY 0.787234 (-9538 8837);
PAINT MONO (-9538 8837);
FORCEPROP 1 LASTPIN (-9350 8825) $PN 2
J 0
(-9388 8837);
DISPLAY 0.787234 (-9388 8837);
PAINT MONO (-9388 8837);
FORCEPROP 1 LAST MATERIAL CHIP
J 0
(-9200 8825);
DISPLAY 0.638298 (-9200 8825);
FORCEPROP 1 LAST VALUE 0
J 2
(-9300 8825);
DISPLAY 0.638298 (-9300 8825);
FORCEPROP 2 LAST CDS_LIB pure_quanta
J 0
(-9450 8825);
DISPLAY INVISIBLE (-9450 8825);
FORCEPROP 1 LAST PACK_TYPE 0402LF
J 0
(-9575 8950);
DISPLAY 0.638298 (-9575 8950);
DISPLAY INVISIBLE (-9575 8950);
FORCEPROP 1 LAST TOLERANCE 5%
J 0
(-9275 8825);
DISPLAY 0.638298 (-9275 8825);
DISPLAY INVISIBLE (-9275 8825);
FORCEPROP 1 LAST WATTAGE 1/16W
J 2
(-9200 8950);
DISPLAY 0.638298 (-9200 8950);
DISPLAY INVISIBLE (-9200 8950);
FORCEPROP 1 LAST PATH I169
J 0
(-9500 8975);
DISPLAY 0.978723 (-9500 8975);
PAINT WHITE (-9500 8975);
DISPLAY INVISIBLE (-9500 8975);
FORCEPROP 1 LAST PART_NUMBER CS00002JB13
J 0
(-9575 8900);
DISPLAY 0.638298 (-9575 8900);
DISPLAY INVISIBLE (-9575 8900);
FORCEADD Q_RES..2
(-15200 4200);
FORCEPROP 1 LAST LOCATION R6035
J 0
(-15155 4325);
DISPLAY 0.978723 (-15155 4325);
FORCEPROP 0 LAST $SEC 1
J 0
(-15150 4375);
DISPLAY 0.680851 (-15150 4375);
PAINT MONO (-15150 4375);
DISPLAY INVISIBLE (-15150 4375);
FORCEPROP 0 LAST CDS_SEC 1
J 0
(-15075 4225);
DISPLAY 0.680851 (-15075 4225);
DISPLAY INVISIBLE (-15075 4225);
FORCEPROP 1 LASTPIN (-15200 4300) $PN 1
J 0
(-15195 4262);
DISPLAY 0.787234 (-15195 4262);
PAINT MONO (-15195 4262);
FORCEPROP 1 LASTPIN (-15200 4100) $PN 2
J 0
(-15195 4110);
DISPLAY 0.787234 (-15195 4110);
PAINT MONO (-15195 4110);
FORCEPROP 1 LAST PACK_TYPE 0402LF
J 0
(-15160 4025);
DISPLAY 0.978723 (-15160 4025);
FORCEPROP 1 LAST MATERIAL EMPTY
J 0
(-15160 4125);
DISPLAY 0.978723 (-15160 4125);
FORCEPROP 1 LAST WATTAGE 1/16W
J 0
(-15160 4175);
DISPLAY 0.978723 (-15160 4175);
FORCEPROP 1 LAST TOLERANCE 5%
J 0
(-15155 4225);
DISPLAY 0.978723 (-15155 4225);
FORCEPROP 1 LAST VALUE 4.7K
J 0
(-15155 4275);
DISPLAY 0.978723 (-15155 4275);
FORCEPROP 2 LAST CDS_LIB pure_quanta
J 0
(-15200 4200);
DISPLAY INVISIBLE (-15200 4200);
FORCEPROP 1 LAST PATH I17
J 0
(-15150 4375);
DISPLAY 0.978723 (-15150 4375);
PAINT WHITE (-15150 4375);
DISPLAY INVISIBLE (-15150 4375);
FORCEPROP 1 LAST PART_NUMBER CS24702JB10
J 0
(-15160 4075);
DISPLAY 0.978723 (-15160 4075);
DISPLAY INVISIBLE (-15160 4075);
FORCEADD UNIVERSAL_GND..1
(-9275 9350);
FORCEPROP 3 LASTPIN (-9275 9400) SIG_NAME GND\g
J 0
(-9265 9410);
DISPLAY 0.659574 (-9265 9410);
PAINT MONO (-9265 9410);
DISPLAY INVISIBLE (-9265 9410);
FORCEPROP 2 LAST CDS_LIB pure_quanta_power
J 0
(-9275 9350);
DISPLAY INVISIBLE (-9275 9350);
FORCEPROP 1 LAST HDL_POWER GND
J 1
(-9250 9275);
DISPLAY 0.702128 (-9250 9275);
PAINT GREEN (-9250 9275);
DISPLAY INVISIBLE (-9250 9275);
FORCEPROP 1 LAST PATH I170
J 0
(-9200 9350);
DISPLAY 0.872340 (-9200 9350);
PAINT AQUA (-9200 9350);
DISPLAY INVISIBLE (-9200 9350);
FORCEADD Q_RES..2
(-9275 9550);
FORCEPROP 1 LAST LOCATION R1801
J 0
(-9230 9675);
DISPLAY 0.638298 (-9230 9675);
FORCEPROP 0 LAST $SEC 1
J 0
(-9225 9725);
DISPLAY 0.680851 (-9225 9725);
PAINT MONO (-9225 9725);
DISPLAY INVISIBLE (-9225 9725);
FORCEPROP 0 LAST CDS_SEC 1
J 0
(-9225 9725);
DISPLAY 1.021277 (-9225 9725);
DISPLAY INVISIBLE (-9225 9725);
FORCEPROP 1 LASTPIN (-9275 9650) $PN 1
J 0
(-9270 9612);
DISPLAY 0.787234 (-9270 9612);
PAINT MONO (-9270 9612);
FORCEPROP 1 LASTPIN (-9275 9450) $PN 2
J 0
(-9270 9460);
DISPLAY 0.787234 (-9270 9460);
PAINT MONO (-9270 9460);
FORCEPROP 1 LAST VALUE 0
J 0
(-9230 9625);
DISPLAY 0.638298 (-9230 9625);
FORCEPROP 1 LAST TOLERANCE 5%
J 0
(-9230 9575);
DISPLAY 0.638298 (-9230 9575);
FORCEPROP 1 LAST WATTAGE 1/16W
J 0
(-9235 9525);
DISPLAY 0.638298 (-9235 9525);
FORCEPROP 1 LAST MATERIAL CHIP
J 0
(-9235 9475);
DISPLAY 0.638298 (-9235 9475);
FORCEPROP 1 LAST PACK_TYPE 0402LF
J 0
(-9235 9375);
DISPLAY 0.638298 (-9235 9375);
FORCEPROP 2 LAST CDS_LIB pure_quanta
J 0
(-9275 9550);
DISPLAY INVISIBLE (-9275 9550);
FORCEPROP 1 LAST PATH I171
J 0
(-9225 9725);
DISPLAY 0.978723 (-9225 9725);
PAINT WHITE (-9225 9725);
DISPLAY INVISIBLE (-9225 9725);
FORCEPROP 1 LAST PART_NUMBER CS00002JB13
J 0
(-9235 9425);
DISPLAY 0.638298 (-9235 9425);
DISPLAY INVISIBLE (-9235 9425);
FORCEADD VCC_CORE..1
(-8700 6950);
FORCEPROP 3 LASTPIN (-8700 6900) SIG_NAME SCM_VDD_RTC\g
J 0
(-8690 6910);
DISPLAY 0.659574 (-8690 6910);
PAINT MONO (-8690 6910);
DISPLAY INVISIBLE (-8690 6910);
FORCEPROP 1 LAST HDL_POWER SCM_VDD_RTC
J 1
(-8700 7000);
DISPLAY 0.489362 (-8700 7000);
PAINT GREEN (-8700 7000);
FORCEPROP 2 LAST CDS_LIB pure_quanta_power
J 0
(-8700 6950);
DISPLAY INVISIBLE (-8700 6950);
FORCEPROP 1 LAST PATH I172
J 0
(-8650 6975);
DISPLAY 0.872340 (-8650 6975);
PAINT AQUA (-8650 6975);
DISPLAY INVISIBLE (-8650 6975);
FORCEADD UNIVERSAL_GND..1
(-8450 8250);
FORCEPROP 3 LASTPIN (-8450 8300) SIG_NAME GND\g
J 0
(-8440 8310);
DISPLAY 0.659574 (-8440 8310);
PAINT MONO (-8440 8310);
DISPLAY INVISIBLE (-8440 8310);
FORCEPROP 2 LAST CDS_LIB pure_quanta_power
J 0
(-8450 8250);
DISPLAY INVISIBLE (-8450 8250);
FORCEPROP 1 LAST HDL_POWER GND
J 1
(-8425 8175);
DISPLAY 0.702128 (-8425 8175);
PAINT GREEN (-8425 8175);
DISPLAY INVISIBLE (-8425 8175);
FORCEPROP 1 LAST PATH I173
J 0
(-8375 8250);
DISPLAY 0.872340 (-8375 8250);
PAINT AQUA (-8375 8250);
DISPLAY INVISIBLE (-8375 8250);
FORCEADD Q_RES..2
(-8450 8475);
FORCEPROP 1 LAST LOCATION R6028
J 0
(-8405 8600);
DISPLAY 0.638298 (-8405 8600);
FORCEPROP 0 LAST $SEC 1
J 0
(-8400 8650);
DISPLAY 0.680851 (-8400 8650);
PAINT MONO (-8400 8650);
DISPLAY INVISIBLE (-8400 8650);
FORCEPROP 0 LAST CDS_SEC 1
J 0
(-8400 8650);
DISPLAY 1.021277 (-8400 8650);
DISPLAY INVISIBLE (-8400 8650);
FORCEPROP 1 LASTPIN (-8450 8575) $PN 1
J 0
(-8445 8537);
DISPLAY 0.787234 (-8445 8537);
PAINT MONO (-8445 8537);
FORCEPROP 1 LASTPIN (-8450 8375) $PN 2
J 0
(-8445 8385);
DISPLAY 0.787234 (-8445 8385);
PAINT MONO (-8445 8385);
FORCEPROP 1 LAST TOLERANCE 5%
J 0
(-8405 8500);
DISPLAY 0.638298 (-8405 8500);
FORCEPROP 1 LAST MATERIAL CHIP
J 0
(-8410 8400);
DISPLAY 0.638298 (-8410 8400);
FORCEPROP 1 LAST PACK_TYPE 0402LF
J 0
(-8410 8300);
DISPLAY 0.638298 (-8410 8300);
FORCEPROP 1 LAST VALUE 0
J 0
(-8405 8550);
DISPLAY 0.638298 (-8405 8550);
FORCEPROP 1 LAST WATTAGE 1/16W
J 0
(-8410 8450);
DISPLAY 0.638298 (-8410 8450);
FORCEPROP 2 LAST CDS_LIB pure_quanta
J 0
(-8450 8475);
DISPLAY INVISIBLE (-8450 8475);
FORCEPROP 1 LAST PATH I174
J 0
(-8400 8650);
DISPLAY 0.978723 (-8400 8650);
PAINT WHITE (-8400 8650);
DISPLAY INVISIBLE (-8400 8650);
FORCEPROP 1 LAST PART_NUMBER CS00002JB13
J 0
(-8410 8350);
DISPLAY 0.638298 (-8410 8350);
DISPLAY INVISIBLE (-8410 8350);
FORCEADD OFFPAGE..2
(-8375 8825);
FORCEPROP 2 LAST $XR0 80 
J 0
(-8186 8825);
DISPLAY 0.638298 (-8186 8825);
PAINT MONO (-8186 8825);
FORCEPROP 2 LAST CDS_LIB standard
J 0
(-8375 8825);
DISPLAY INVISIBLE (-8375 8825);
FORCEPROP 1 LAST OFFPAGE TRUE
J 0
(-8050 8700);
DISPLAY 0.872340 (-8050 8700);
PAINT GREEN (-8050 8700);
DISPLAY INVISIBLE (-8050 8700);
FORCEPROP 1 LAST COMMENT_BODY TRUE
J 0
(-8420 8730);
DISPLAY 0.872340 (-8420 8730);
PAINT PEACH (-8420 8730);
DISPLAY INVISIBLE (-8420 8730);
FORCEPROP 2 LAST PATH I175
J 0
(-8200 8900);
DISPLAY 0.680851 (-8200 8900);
DISPLAY INVISIBLE (-8200 8900);
FORCEADD SCONN168_ME1016810202011..1
R 2
(-12050 7100);
FORCEPROP 1 LAST LOCATION J41
J 2
(-11561 9867);
DISPLAY 0.723404 (-11561 9867);
PAINT GREEN (-11561 9867);
FORCEPROP 2 LAST SEC 1
J 2
(-11575 10025);
DISPLAY 0.680851 (-11575 10025);
PAINT MONO (-11575 10025);
DISPLAY INVISIBLE (-11575 10025);
FORCEPROP 2 LASTPIN (-11400 8175) $PN B11
J 0
(-11390 8185);
DISPLAY 0.680851 (-11390 8185);
PAINT MONO (-11390 8185);
FORCEPROP 2 LASTPIN (-11400 8675) $PN B1
J 0
(-11390 8685);
DISPLAY 0.680851 (-11390 8685);
PAINT MONO (-11390 8685);
FORCEPROP 2 LASTPIN (-11400 8625) $PN B2
J 0
(-11390 8635);
DISPLAY 0.680851 (-11390 8635);
PAINT MONO (-11390 8635);
FORCEPROP 2 LASTPIN (-11400 8575) $PN B3
J 0
(-11390 8585);
DISPLAY 0.680851 (-11390 8585);
PAINT MONO (-11390 8585);
FORCEPROP 2 LASTPIN (-11400 8525) $PN B4
J 0
(-11390 8535);
DISPLAY 0.680851 (-11390 8535);
PAINT MONO (-11390 8535);
FORCEPROP 2 LASTPIN (-11400 8475) $PN B5
J 0
(-11390 8485);
DISPLAY 0.680851 (-11390 8485);
PAINT MONO (-11390 8485);
FORCEPROP 2 LASTPIN (-11400 8425) $PN B6
J 0
(-11390 8435);
DISPLAY 0.680851 (-11390 8435);
PAINT MONO (-11390 8435);
FORCEPROP 2 LASTPIN (-11400 8125) $PN B12
J 0
(-11390 8135);
DISPLAY 0.680851 (-11390 8135);
PAINT MONO (-11390 8135);
FORCEPROP 2 LASTPIN (-11400 8375) $PN B7
J 0
(-11390 8385);
DISPLAY 0.680851 (-11390 8385);
PAINT MONO (-11390 8385);
FORCEPROP 2 LASTPIN (-11400 8325) $PN B8
J 0
(-11390 8335);
DISPLAY 0.680851 (-11390 8335);
PAINT MONO (-11390 8335);
FORCEPROP 2 LASTPIN (-11400 8275) $PN B9
J 0
(-11390 8285);
DISPLAY 0.680851 (-11390 8285);
PAINT MONO (-11390 8285);
FORCEPROP 2 LASTPIN (-11400 9225) $PN OB6
J 0
(-11390 9235);
DISPLAY 0.680851 (-11390 9235);
PAINT MONO (-11390 9235);
FORCEPROP 2 LASTPIN (-11400 9325) $PN OB4
J 0
(-11390 9335);
DISPLAY 0.680851 (-11390 9335);
PAINT MONO (-11390 9335);
FORCEPROP 2 LASTPIN (-11400 9275) $PN OB5
J 0
(-11390 9285);
DISPLAY 0.680851 (-11390 9285);
PAINT MONO (-11390 9285);
FORCEPROP 2 LASTPIN (-12700 4925) $PN G1
J 2
(-12710 4935);
DISPLAY 0.680851 (-12710 4935);
PAINT MONO (-12710 4935);
FORCEPROP 2 LASTPIN (-12700 4875) $PN G2
J 2
(-12710 4885);
DISPLAY 0.680851 (-12710 4885);
PAINT MONO (-12710 4885);
FORCEPROP 2 LASTPIN (-12700 4825) $PN G3
J 2
(-12710 4835);
DISPLAY 0.680851 (-12710 4835);
PAINT MONO (-12710 4835);
FORCEPROP 2 LASTPIN (-12700 4775) $PN G4
J 2
(-12710 4785);
DISPLAY 0.680851 (-12710 4785);
PAINT MONO (-12710 4785);
FORCEPROP 2 LASTPIN (-12700 4725) $PN G5
J 2
(-12710 4735);
DISPLAY 0.680851 (-12710 4735);
PAINT MONO (-12710 4735);
FORCEPROP 2 LASTPIN (-12700 8675) $PN A1
J 2
(-12710 8685);
DISPLAY 0.680851 (-12710 8685);
PAINT MONO (-12710 8685);
FORCEPROP 2 LASTPIN (-12700 8625) $PN A2
J 2
(-12710 8635);
DISPLAY 0.680851 (-12710 8635);
PAINT MONO (-12710 8635);
FORCEPROP 2 LASTPIN (-12700 8575) $PN A3
J 2
(-12710 8585);
DISPLAY 0.680851 (-12710 8585);
PAINT MONO (-12710 8585);
FORCEPROP 2 LASTPIN (-12700 8525) $PN A4
J 2
(-12710 8535);
DISPLAY 0.680851 (-12710 8535);
PAINT MONO (-12710 8535);
FORCEPROP 2 LASTPIN (-12700 8475) $PN A5
J 2
(-12710 8485);
DISPLAY 0.680851 (-12710 8485);
PAINT MONO (-12710 8485);
FORCEPROP 2 LASTPIN (-12700 8425) $PN A6
J 2
(-12710 8435);
DISPLAY 0.680851 (-12710 8435);
PAINT MONO (-12710 8435);
FORCEPROP 2 LASTPIN (-12700 8075) $PN A13
J 2
(-12710 8085);
DISPLAY 0.680851 (-12710 8085);
PAINT MONO (-12710 8085);
FORCEPROP 2 LASTPIN (-12700 7925) $PN A16
J 2
(-12710 7935);
DISPLAY 0.680851 (-12710 7935);
PAINT MONO (-12710 7935);
FORCEPROP 2 LASTPIN (-12700 7775) $PN A19
J 2
(-12710 7785);
DISPLAY 0.680851 (-12710 7785);
PAINT MONO (-12710 7785);
FORCEPROP 2 LASTPIN (-12700 7625) $PN A22
J 2
(-12710 7635);
DISPLAY 0.680851 (-12710 7635);
PAINT MONO (-12710 7635);
FORCEPROP 2 LASTPIN (-12700 7475) $PN A25
J 2
(-12710 7485);
DISPLAY 0.680851 (-12710 7485);
PAINT MONO (-12710 7485);
FORCEPROP 2 LASTPIN (-12700 7325) $PN A28
J 2
(-12710 7335);
DISPLAY 0.680851 (-12710 7335);
PAINT MONO (-12710 7335);
FORCEPROP 2 LASTPIN (-12700 7175) $PN A29
J 2
(-12710 7185);
DISPLAY 0.680851 (-12710 7185);
PAINT MONO (-12710 7185);
FORCEPROP 2 LASTPIN (-12700 7025) $PN A32
J 2
(-12710 7035);
DISPLAY 0.680851 (-12710 7035);
PAINT MONO (-12710 7035);
FORCEPROP 2 LASTPIN (-12700 6875) $PN A35
J 2
(-12710 6885);
DISPLAY 0.680851 (-12710 6885);
PAINT MONO (-12710 6885);
FORCEPROP 2 LASTPIN (-12700 6725) $PN A38
J 2
(-12710 6735);
DISPLAY 0.680851 (-12710 6735);
PAINT MONO (-12710 6735);
FORCEPROP 2 LASTPIN (-12700 6575) $PN A41
J 2
(-12710 6585);
DISPLAY 0.680851 (-12710 6585);
PAINT MONO (-12710 6585);
FORCEPROP 2 LASTPIN (-12700 6375) $PN A43
J 2
(-12710 6385);
DISPLAY 0.680851 (-12710 6385);
PAINT MONO (-12710 6385);
FORCEPROP 2 LASTPIN (-12700 6225) $PN A46
J 2
(-12710 6235);
DISPLAY 0.680851 (-12710 6235);
PAINT MONO (-12710 6235);
FORCEPROP 2 LASTPIN (-12700 6075) $PN A49
J 2
(-12710 6085);
DISPLAY 0.680851 (-12710 6085);
PAINT MONO (-12710 6085);
FORCEPROP 2 LASTPIN (-12700 5925) $PN A52
J 2
(-12710 5935);
DISPLAY 0.680851 (-12710 5935);
PAINT MONO (-12710 5935);
FORCEPROP 2 LASTPIN (-12700 5775) $PN A55
J 2
(-12710 5785);
DISPLAY 0.680851 (-12710 5785);
PAINT MONO (-12710 5785);
FORCEPROP 2 LASTPIN (-12700 5625) $PN A58
J 2
(-12710 5635);
DISPLAY 0.680851 (-12710 5635);
PAINT MONO (-12710 5635);
FORCEPROP 2 LASTPIN (-12700 5475) $PN A61
J 2
(-12710 5485);
DISPLAY 0.680851 (-12710 5485);
PAINT MONO (-12710 5485);
FORCEPROP 2 LASTPIN (-12700 5325) $PN A64
J 2
(-12710 5335);
DISPLAY 0.680851 (-12710 5335);
PAINT MONO (-12710 5335);
FORCEPROP 2 LASTPIN (-12700 5175) $PN A67
J 2
(-12710 5185);
DISPLAY 0.680851 (-12710 5185);
PAINT MONO (-12710 5185);
FORCEPROP 2 LASTPIN (-11400 8075) $PN B13
J 0
(-11390 8085);
DISPLAY 0.680851 (-11390 8085);
PAINT MONO (-11390 8085);
FORCEPROP 2 LASTPIN (-11400 7925) $PN B16
J 0
(-11390 7935);
DISPLAY 0.680851 (-11390 7935);
PAINT MONO (-11390 7935);
FORCEPROP 2 LASTPIN (-11400 7775) $PN B19
J 0
(-11390 7785);
DISPLAY 0.680851 (-11390 7785);
PAINT MONO (-11390 7785);
FORCEPROP 2 LASTPIN (-11400 7625) $PN B22
J 0
(-11390 7635);
DISPLAY 0.680851 (-11390 7635);
PAINT MONO (-11390 7635);
FORCEPROP 2 LASTPIN (-11400 7475) $PN B25
J 0
(-11390 7485);
DISPLAY 0.680851 (-11390 7485);
PAINT MONO (-11390 7485);
FORCEPROP 2 LASTPIN (-11400 7325) $PN B28
J 0
(-11390 7335);
DISPLAY 0.680851 (-11390 7335);
PAINT MONO (-11390 7335);
FORCEPROP 2 LASTPIN (-11400 7175) $PN B29
J 0
(-11390 7185);
DISPLAY 0.680851 (-11390 7185);
PAINT MONO (-11390 7185);
FORCEPROP 2 LASTPIN (-11400 7025) $PN B32
J 0
(-11390 7035);
DISPLAY 0.680851 (-11390 7035);
PAINT MONO (-11390 7035);
FORCEPROP 2 LASTPIN (-11400 6875) $PN B35
J 0
(-11390 6885);
DISPLAY 0.680851 (-11390 6885);
PAINT MONO (-11390 6885);
FORCEPROP 2 LASTPIN (-11400 6725) $PN B38
J 0
(-11390 6735);
DISPLAY 0.680851 (-11390 6735);
PAINT MONO (-11390 6735);
FORCEPROP 2 LASTPIN (-11400 6575) $PN B41
J 0
(-11390 6585);
DISPLAY 0.680851 (-11390 6585);
PAINT MONO (-11390 6585);
FORCEPROP 2 LASTPIN (-11400 6375) $PN B43
J 0
(-11390 6385);
DISPLAY 0.680851 (-11390 6385);
PAINT MONO (-11390 6385);
FORCEPROP 2 LASTPIN (-11400 6225) $PN B46
J 0
(-11390 6235);
DISPLAY 0.680851 (-11390 6235);
PAINT MONO (-11390 6235);
FORCEPROP 2 LASTPIN (-11400 6075) $PN B49
J 0
(-11390 6085);
DISPLAY 0.680851 (-11390 6085);
PAINT MONO (-11390 6085);
FORCEPROP 2 LASTPIN (-11400 5925) $PN B52
J 0
(-11390 5935);
DISPLAY 0.680851 (-11390 5935);
PAINT MONO (-11390 5935);
FORCEPROP 2 LASTPIN (-11400 5775) $PN B55
J 0
(-11390 5785);
DISPLAY 0.680851 (-11390 5785);
PAINT MONO (-11390 5785);
FORCEPROP 2 LASTPIN (-11400 5625) $PN B58
J 0
(-11390 5635);
DISPLAY 0.680851 (-11390 5635);
PAINT MONO (-11390 5635);
FORCEPROP 2 LASTPIN (-11400 5475) $PN B61
J 0
(-11390 5485);
DISPLAY 0.680851 (-11390 5485);
PAINT MONO (-11390 5485);
FORCEPROP 2 LASTPIN (-11400 5325) $PN B64
J 0
(-11390 5335);
DISPLAY 0.680851 (-11390 5335);
PAINT MONO (-11390 5335);
FORCEPROP 2 LASTPIN (-11400 5175) $PN B67
J 0
(-11390 5185);
DISPLAY 0.680851 (-11390 5185);
PAINT MONO (-11390 5185);
FORCEPROP 2 LASTPIN (-12700 9025) $PN OA10
J 2
(-12710 9035);
DISPLAY 0.680851 (-12710 9035);
PAINT MONO (-12710 9035);
FORCEPROP 2 LASTPIN (-12700 8875) $PN OA13
J 2
(-12710 8885);
DISPLAY 0.680851 (-12710 8885);
PAINT MONO (-12710 8885);
FORCEPROP 2 LASTPIN (-11400 9025) $PN OB10
J 0
(-11390 9035);
DISPLAY 0.680851 (-11390 9035);
PAINT MONO (-11390 9035);
FORCEPROP 2 LASTPIN (-11400 8875) $PN OB13
J 0
(-11390 8885);
DISPLAY 0.680851 (-11390 8885);
PAINT MONO (-11390 8885);
FORCEPROP 2 LASTPIN (-11400 9375) $PN OB3
J 0
(-11390 9385);
DISPLAY 0.680851 (-11390 9385);
PAINT MONO (-11390 9385);
FORCEPROP 2 LASTPIN (-11400 9425) $PN OB2
J 0
(-11390 9435);
DISPLAY 0.680851 (-11390 9435);
PAINT MONO (-11390 9435);
FORCEPROP 2 LASTPIN (-11400 9475) $PN OB1
J 0
(-11390 9485);
DISPLAY 0.680851 (-11390 9485);
PAINT MONO (-11390 9485);
FORCEPROP 2 LASTPIN (-12700 7875) $PN A17
J 2
(-12710 7885);
DISPLAY 0.680851 (-12710 7885);
PAINT MONO (-12710 7885);
FORCEPROP 2 LASTPIN (-12700 7725) $PN A20
J 2
(-12710 7735);
DISPLAY 0.680851 (-12710 7735);
PAINT MONO (-12710 7735);
FORCEPROP 2 LASTPIN (-12700 7575) $PN A23
J 2
(-12710 7585);
DISPLAY 0.680851 (-12710 7585);
PAINT MONO (-12710 7585);
FORCEPROP 2 LASTPIN (-12700 7425) $PN A26
J 2
(-12710 7435);
DISPLAY 0.680851 (-12710 7435);
PAINT MONO (-12710 7435);
FORCEPROP 2 LASTPIN (-12700 7125) $PN A30
J 2
(-12710 7135);
DISPLAY 0.680851 (-12710 7135);
PAINT MONO (-12710 7135);
FORCEPROP 2 LASTPIN (-12700 6975) $PN A33
J 2
(-12710 6985);
DISPLAY 0.680851 (-12710 6985);
PAINT MONO (-12710 6985);
FORCEPROP 2 LASTPIN (-12700 6825) $PN A36
J 2
(-12710 6835);
DISPLAY 0.680851 (-12710 6835);
PAINT MONO (-12710 6835);
FORCEPROP 2 LASTPIN (-12700 6675) $PN A39
J 2
(-12710 6685);
DISPLAY 0.680851 (-12710 6685);
PAINT MONO (-12710 6685);
FORCEPROP 2 LASTPIN (-12700 6325) $PN A44
J 2
(-12710 6335);
DISPLAY 0.680851 (-12710 6335);
PAINT MONO (-12710 6335);
FORCEPROP 2 LASTPIN (-12700 6175) $PN A47
J 2
(-12710 6185);
DISPLAY 0.680851 (-12710 6185);
PAINT MONO (-12710 6185);
FORCEPROP 2 LASTPIN (-12700 6025) $PN A50
J 2
(-12710 6035);
DISPLAY 0.680851 (-12710 6035);
PAINT MONO (-12710 6035);
FORCEPROP 2 LASTPIN (-12700 5875) $PN A53
J 2
(-12710 5885);
DISPLAY 0.680851 (-12710 5885);
PAINT MONO (-12710 5885);
FORCEPROP 2 LASTPIN (-12700 5725) $PN A56
J 2
(-12710 5735);
DISPLAY 0.680851 (-12710 5735);
PAINT MONO (-12710 5735);
FORCEPROP 2 LASTPIN (-12700 5575) $PN A59
J 2
(-12710 5585);
DISPLAY 0.680851 (-12710 5585);
PAINT MONO (-12710 5585);
FORCEPROP 2 LASTPIN (-12700 5425) $PN A62
J 2
(-12710 5435);
DISPLAY 0.680851 (-12710 5435);
PAINT MONO (-12710 5435);
FORCEPROP 2 LASTPIN (-12700 5275) $PN A65
J 2
(-12710 5285);
DISPLAY 0.680851 (-12710 5285);
PAINT MONO (-12710 5285);
FORCEPROP 2 LASTPIN (-12700 7825) $PN A18
J 2
(-12710 7835);
DISPLAY 0.680851 (-12710 7835);
PAINT MONO (-12710 7835);
FORCEPROP 2 LASTPIN (-12700 7675) $PN A21
J 2
(-12710 7685);
DISPLAY 0.680851 (-12710 7685);
PAINT MONO (-12710 7685);
FORCEPROP 2 LASTPIN (-12700 7525) $PN A24
J 2
(-12710 7535);
DISPLAY 0.680851 (-12710 7535);
PAINT MONO (-12710 7535);
FORCEPROP 2 LASTPIN (-12700 7375) $PN A27
J 2
(-12710 7385);
DISPLAY 0.680851 (-12710 7385);
PAINT MONO (-12710 7385);
FORCEPROP 2 LASTPIN (-12700 7075) $PN A31
J 2
(-12710 7085);
DISPLAY 0.680851 (-12710 7085);
PAINT MONO (-12710 7085);
FORCEPROP 2 LASTPIN (-12700 6925) $PN A34
J 2
(-12710 6935);
DISPLAY 0.680851 (-12710 6935);
PAINT MONO (-12710 6935);
FORCEPROP 2 LASTPIN (-12700 6775) $PN A37
J 2
(-12710 6785);
DISPLAY 0.680851 (-12710 6785);
PAINT MONO (-12710 6785);
FORCEPROP 2 LASTPIN (-12700 6625) $PN A40
J 2
(-12710 6635);
DISPLAY 0.680851 (-12710 6635);
PAINT MONO (-12710 6635);
FORCEPROP 2 LASTPIN (-12700 6275) $PN A45
J 2
(-12710 6285);
DISPLAY 0.680851 (-12710 6285);
PAINT MONO (-12710 6285);
FORCEPROP 2 LASTPIN (-12700 6125) $PN A48
J 2
(-12710 6135);
DISPLAY 0.680851 (-12710 6135);
PAINT MONO (-12710 6135);
FORCEPROP 2 LASTPIN (-12700 5975) $PN A51
J 2
(-12710 5985);
DISPLAY 0.680851 (-12710 5985);
PAINT MONO (-12710 5985);
FORCEPROP 2 LASTPIN (-12700 5825) $PN A54
J 2
(-12710 5835);
DISPLAY 0.680851 (-12710 5835);
PAINT MONO (-12710 5835);
FORCEPROP 2 LASTPIN (-12700 5675) $PN A57
J 2
(-12710 5685);
DISPLAY 0.680851 (-12710 5685);
PAINT MONO (-12710 5685);
FORCEPROP 2 LASTPIN (-12700 5525) $PN A60
J 2
(-12710 5535);
DISPLAY 0.680851 (-12710 5535);
PAINT MONO (-12710 5535);
FORCEPROP 2 LASTPIN (-12700 5375) $PN A63
J 2
(-12710 5385);
DISPLAY 0.680851 (-12710 5385);
PAINT MONO (-12710 5385);
FORCEPROP 2 LASTPIN (-12700 5225) $PN A66
J 2
(-12710 5235);
DISPLAY 0.680851 (-12710 5235);
PAINT MONO (-12710 5235);
FORCEPROP 2 LASTPIN (-11400 8225) $PN B10
J 0
(-11390 8235);
DISPLAY 0.680851 (-11390 8235);
PAINT MONO (-11390 8235);
FORCEPROP 2 LASTPIN (-12700 8175) $PN A11
J 2
(-12710 8185);
DISPLAY 0.680851 (-12710 8185);
PAINT MONO (-12710 8185);
FORCEPROP 2 LASTPIN (-12700 9475) $PN OA1
J 2
(-12710 9485);
DISPLAY 0.680851 (-12710 9485);
PAINT MONO (-12710 9485);
FORCEPROP 2 LASTPIN (-12700 9425) $PN OA2
J 2
(-12710 9435);
DISPLAY 0.680851 (-12710 9435);
PAINT MONO (-12710 9435);
FORCEPROP 2 LASTPIN (-11400 7875) $PN B17
J 0
(-11390 7885);
DISPLAY 0.680851 (-11390 7885);
PAINT MONO (-11390 7885);
FORCEPROP 2 LASTPIN (-11400 7725) $PN B20
J 0
(-11390 7735);
DISPLAY 0.680851 (-11390 7735);
PAINT MONO (-11390 7735);
FORCEPROP 2 LASTPIN (-11400 7575) $PN B23
J 0
(-11390 7585);
DISPLAY 0.680851 (-11390 7585);
PAINT MONO (-11390 7585);
FORCEPROP 2 LASTPIN (-11400 7425) $PN B26
J 0
(-11390 7435);
DISPLAY 0.680851 (-11390 7435);
PAINT MONO (-11390 7435);
FORCEPROP 2 LASTPIN (-11400 7125) $PN B30
J 0
(-11390 7135);
DISPLAY 0.680851 (-11390 7135);
PAINT MONO (-11390 7135);
FORCEPROP 2 LASTPIN (-11400 6975) $PN B33
J 0
(-11390 6985);
DISPLAY 0.680851 (-11390 6985);
PAINT MONO (-11390 6985);
FORCEPROP 2 LASTPIN (-11400 6825) $PN B36
J 0
(-11390 6835);
DISPLAY 0.680851 (-11390 6835);
PAINT MONO (-11390 6835);
FORCEPROP 2 LASTPIN (-11400 6675) $PN B39
J 0
(-11390 6685);
DISPLAY 0.680851 (-11390 6685);
PAINT MONO (-11390 6685);
FORCEPROP 2 LASTPIN (-11400 6325) $PN B44
J 0
(-11390 6335);
DISPLAY 0.680851 (-11390 6335);
PAINT MONO (-11390 6335);
FORCEPROP 2 LASTPIN (-11400 6175) $PN B47
J 0
(-11390 6185);
DISPLAY 0.680851 (-11390 6185);
PAINT MONO (-11390 6185);
FORCEPROP 2 LASTPIN (-11400 6025) $PN B50
J 0
(-11390 6035);
DISPLAY 0.680851 (-11390 6035);
PAINT MONO (-11390 6035);
FORCEPROP 2 LASTPIN (-11400 5875) $PN B53
J 0
(-11390 5885);
DISPLAY 0.680851 (-11390 5885);
PAINT MONO (-11390 5885);
FORCEPROP 2 LASTPIN (-11400 5725) $PN B56
J 0
(-11390 5735);
DISPLAY 0.680851 (-11390 5735);
PAINT MONO (-11390 5735);
FORCEPROP 2 LASTPIN (-11400 5575) $PN B59
J 0
(-11390 5585);
DISPLAY 0.680851 (-11390 5585);
PAINT MONO (-11390 5585);
FORCEPROP 2 LASTPIN (-11400 5425) $PN B62
J 0
(-11390 5435);
DISPLAY 0.680851 (-11390 5435);
PAINT MONO (-11390 5435);
FORCEPROP 2 LASTPIN (-11400 5275) $PN B65
J 0
(-11390 5285);
DISPLAY 0.680851 (-11390 5285);
PAINT MONO (-11390 5285);
FORCEPROP 2 LASTPIN (-11400 7825) $PN B18
J 0
(-11390 7835);
DISPLAY 0.680851 (-11390 7835);
PAINT MONO (-11390 7835);
FORCEPROP 2 LASTPIN (-11400 7675) $PN B21
J 0
(-11390 7685);
DISPLAY 0.680851 (-11390 7685);
PAINT MONO (-11390 7685);
FORCEPROP 2 LASTPIN (-11400 7525) $PN B24
J 0
(-11390 7535);
DISPLAY 0.680851 (-11390 7535);
PAINT MONO (-11390 7535);
FORCEPROP 2 LASTPIN (-11400 7375) $PN B27
J 0
(-11390 7385);
DISPLAY 0.680851 (-11390 7385);
PAINT MONO (-11390 7385);
FORCEPROP 2 LASTPIN (-11400 7075) $PN B31
J 0
(-11390 7085);
DISPLAY 0.680851 (-11390 7085);
PAINT MONO (-11390 7085);
FORCEPROP 2 LASTPIN (-11400 6925) $PN B34
J 0
(-11390 6935);
DISPLAY 0.680851 (-11390 6935);
PAINT MONO (-11390 6935);
FORCEPROP 2 LASTPIN (-11400 6775) $PN B37
J 0
(-11390 6785);
DISPLAY 0.680851 (-11390 6785);
PAINT MONO (-11390 6785);
FORCEPROP 2 LASTPIN (-11400 6625) $PN B40
J 0
(-11390 6635);
DISPLAY 0.680851 (-11390 6635);
PAINT MONO (-11390 6635);
FORCEPROP 2 LASTPIN (-11400 6275) $PN B45
J 0
(-11390 6285);
DISPLAY 0.680851 (-11390 6285);
PAINT MONO (-11390 6285);
FORCEPROP 2 LASTPIN (-11400 6125) $PN B48
J 0
(-11390 6135);
DISPLAY 0.680851 (-11390 6135);
PAINT MONO (-11390 6135);
FORCEPROP 2 LASTPIN (-11400 5975) $PN B51
J 0
(-11390 5985);
DISPLAY 0.680851 (-11390 5985);
PAINT MONO (-11390 5985);
FORCEPROP 2 LASTPIN (-11400 5825) $PN B54
J 0
(-11390 5835);
DISPLAY 0.680851 (-11390 5835);
PAINT MONO (-11390 5835);
FORCEPROP 2 LASTPIN (-11400 5675) $PN B57
J 0
(-11390 5685);
DISPLAY 0.680851 (-11390 5685);
PAINT MONO (-11390 5685);
FORCEPROP 2 LASTPIN (-11400 5525) $PN B60
J 0
(-11390 5535);
DISPLAY 0.680851 (-11390 5535);
PAINT MONO (-11390 5535);
FORCEPROP 2 LASTPIN (-11400 5375) $PN B63
J 0
(-11390 5385);
DISPLAY 0.680851 (-11390 5385);
PAINT MONO (-11390 5385);
FORCEPROP 2 LASTPIN (-11400 5225) $PN B66
J 0
(-11390 5235);
DISPLAY 0.680851 (-11390 5235);
PAINT MONO (-11390 5235);
FORCEPROP 2 LASTPIN (-12700 8225) $PN A10
J 2
(-12710 8235);
DISPLAY 0.680851 (-12710 8235);
PAINT MONO (-12710 8235);
FORCEPROP 2 LASTPIN (-11400 6525) $PN B42
J 0
(-11390 6535);
DISPLAY 0.680851 (-11390 6535);
PAINT MONO (-11390 6535);
FORCEPROP 2 LASTPIN (-12700 6525) $PN A42
J 2
(-12710 6535);
DISPLAY 0.680851 (-12710 6535);
PAINT MONO (-12710 6535);
FORCEPROP 2 LASTPIN (-12700 8125) $PN A12
J 2
(-12710 8135);
DISPLAY 0.680851 (-12710 8135);
PAINT MONO (-12710 8135);
FORCEPROP 2 LASTPIN (-11400 5025) $PN B70
J 0
(-11390 5035);
DISPLAY 0.680851 (-11390 5035);
PAINT MONO (-11390 5035);
FORCEPROP 2 LASTPIN (-12700 5025) $PN A70
J 2
(-12710 5035);
DISPLAY 0.680851 (-12710 5035);
PAINT MONO (-12710 5035);
FORCEPROP 2 LASTPIN (-12700 9325) $PN OA4
J 2
(-12710 9335);
DISPLAY 0.680851 (-12710 9335);
PAINT MONO (-12710 9335);
FORCEPROP 2 LASTPIN (-12700 9275) $PN OA5
J 2
(-12710 9285);
DISPLAY 0.680851 (-12710 9285);
PAINT MONO (-12710 9285);
FORCEPROP 2 LASTPIN (-12700 8825) $PN OA14
J 2
(-12710 8835);
DISPLAY 0.680851 (-12710 8835);
PAINT MONO (-12710 8835);
FORCEPROP 2 LASTPIN (-11400 8825) $PN OB14
J 0
(-11390 8835);
DISPLAY 0.680851 (-11390 8835);
PAINT MONO (-11390 8835);
FORCEPROP 2 LASTPIN (-11400 9075) $PN OB9
J 0
(-11390 9085);
DISPLAY 0.680851 (-11390 9085);
PAINT MONO (-11390 9085);
FORCEPROP 2 LASTPIN (-11400 9125) $PN OB8
J 0
(-11390 9135);
DISPLAY 0.680851 (-11390 9135);
PAINT MONO (-11390 9135);
FORCEPROP 2 LASTPIN (-12700 9175) $PN OA7
J 2
(-12710 9185);
DISPLAY 0.680851 (-12710 9185);
PAINT MONO (-12710 9185);
FORCEPROP 2 LASTPIN (-12700 9075) $PN OA9
J 2
(-12710 9085);
DISPLAY 0.680851 (-12710 9085);
PAINT MONO (-12710 9085);
FORCEPROP 2 LASTPIN (-12700 9125) $PN OA8
J 2
(-12710 9135);
DISPLAY 0.680851 (-12710 9135);
PAINT MONO (-12710 9135);
FORCEPROP 2 LASTPIN (-11400 8025) $PN B14
J 0
(-11390 8035);
DISPLAY 0.680851 (-11390 8035);
PAINT MONO (-11390 8035);
FORCEPROP 2 LASTPIN (-12700 8025) $PN A14
J 2
(-12710 8035);
DISPLAY 0.680851 (-12710 8035);
PAINT MONO (-12710 8035);
FORCEPROP 2 LASTPIN (-11400 8975) $PN OB11
J 0
(-11390 8985);
DISPLAY 0.680851 (-11390 8985);
PAINT MONO (-11390 8985);
FORCEPROP 2 LASTPIN (-12700 8975) $PN OA11
J 2
(-12710 8985);
DISPLAY 0.680851 (-12710 8985);
PAINT MONO (-12710 8985);
FORCEPROP 2 LASTPIN (-11400 7975) $PN B15
J 0
(-11390 7985);
DISPLAY 0.680851 (-11390 7985);
PAINT MONO (-11390 7985);
FORCEPROP 2 LASTPIN (-12700 7975) $PN A15
J 2
(-12710 7985);
DISPLAY 0.680851 (-12710 7985);
PAINT MONO (-12710 7985);
FORCEPROP 2 LASTPIN (-11400 8925) $PN OB12
J 0
(-11390 8935);
DISPLAY 0.680851 (-11390 8935);
PAINT MONO (-11390 8935);
FORCEPROP 2 LASTPIN (-12700 8925) $PN OA12
J 2
(-12710 8935);
DISPLAY 0.680851 (-12710 8935);
PAINT MONO (-12710 8935);
FORCEPROP 2 LASTPIN (-11400 5125) $PN B68
J 0
(-11390 5135);
DISPLAY 0.680851 (-11390 5135);
PAINT MONO (-11390 5135);
FORCEPROP 2 LASTPIN (-11400 5075) $PN B69
J 0
(-11390 5085);
DISPLAY 0.680851 (-11390 5085);
PAINT MONO (-11390 5085);
FORCEPROP 2 LASTPIN (-11400 9175) $PN OB7
J 0
(-11390 9185);
DISPLAY 0.680851 (-11390 9185);
PAINT MONO (-11390 9185);
FORCEPROP 2 LASTPIN (-12700 9225) $PN OA6
J 2
(-12710 9235);
DISPLAY 0.680851 (-12710 9235);
PAINT MONO (-12710 9235);
FORCEPROP 2 LASTPIN (-12700 8375) $PN A7
J 2
(-12710 8385);
DISPLAY 0.680851 (-12710 8385);
PAINT MONO (-12710 8385);
FORCEPROP 2 LASTPIN (-12700 8325) $PN A8
J 2
(-12710 8335);
DISPLAY 0.680851 (-12710 8335);
PAINT MONO (-12710 8335);
FORCEPROP 2 LASTPIN (-12700 8275) $PN A9
J 2
(-12710 8285);
DISPLAY 0.680851 (-12710 8285);
PAINT MONO (-12710 8285);
FORCEPROP 2 LASTPIN (-12700 5125) $PN A68
J 2
(-12710 5135);
DISPLAY 0.680851 (-12710 5135);
PAINT MONO (-12710 5135);
FORCEPROP 2 LASTPIN (-12700 5075) $PN A69
J 2
(-12710 5085);
DISPLAY 0.680851 (-12710 5085);
PAINT MONO (-12710 5085);
FORCEPROP 2 LASTPIN (-12700 9375) $PN OA3
J 2
(-12710 9385);
DISPLAY 0.680851 (-12710 9385);
PAINT MONO (-12710 9385);
FORCEPROP 2 LAST PART_TYPE SMLF
J 2
(-11575 9975);
DISPLAY 1.021277 (-11575 9975);
FORCEPROP 2 LAST VALUE SCONN168_ME1016810202011
J 2
(-11575 9925);
DISPLAY 1.021277 (-11575 9925);
FORCEPROP 1 LAST MATERIAL IO
J 2
(-11561 9593);
DISPLAY 0.723404 (-11561 9593);
PAINT GREEN (-11561 9593);
FORCEPROP 2 LAST CDS_LIB pure_quanta
J 2
(-12050 7100);
DISPLAY INVISIBLE (-12050 7100);
FORCEPROP 1 LAST NEEDS_NO_SIZE TRUE
J 2
(-12050 7100);
DISPLAY 0.723404 (-12050 7100);
PAINT GREEN (-12050 7100);
DISPLAY INVISIBLE (-12050 7100);
FORCEPROP 1 LAST CDS_LMAN_SYM_OUTLINE -500,2475,500,-2475
J 2
(-12050 7100);
DISPLAY 0.468085 (-12050 7100);
PAINT GREEN (-12050 7100);
DISPLAY INVISIBLE (-12050 7100);
FORCEPROP 2 LAST SEC_TYPE 
J 2
(-11575 10025);
DISPLAY 1.021277 (-11575 10025);
DISPLAY INVISIBLE (-11575 10025);
FORCEPROP 1 LAST PATH I176
J 2
(-12050 7100);
DISPLAY 0.723404 (-12050 7100);
PAINT GREEN (-12050 7100);
DISPLAY INVISIBLE (-12050 7100);
FORCEPROP 1 LAST PART_NUMBER DFHSG8FR011
J 2
(-11561 9720);
DISPLAY 0.723404 (-11561 9720);
PAINT GREEN (-11561 9720);
DISPLAY INVISIBLE (-11561 9720);
FORCEADD Q_RES..1
(-9825 9125);
FORCEPROP 1 LAST LOCATION R6064
J 0
(-10025 9125);
DISPLAY 0.638298 (-10025 9125);
FORCEPROP 0 LAST $SEC 1
J 0
(-9575 9175);
DISPLAY 0.680851 (-9575 9175);
PAINT MONO (-9575 9175);
DISPLAY INVISIBLE (-9575 9175);
FORCEPROP 0 LAST CDS_SEC 1
J 0
(-9575 9175);
DISPLAY 1.021277 (-9575 9175);
DISPLAY INVISIBLE (-9575 9175);
FORCEPROP 1 LASTPIN (-9925 9125) $PN 1
J 0
(-9913 9137);
DISPLAY 0.787234 (-9913 9137);
PAINT MONO (-9913 9137);
FORCEPROP 1 LASTPIN (-9725 9125) $PN 2
J 0
(-9763 9137);
DISPLAY 0.787234 (-9763 9137);
PAINT MONO (-9763 9137);
FORCEPROP 1 LAST MATERIAL EMPTY
J 0
(-9575 9125);
DISPLAY 0.638298 (-9575 9125);
FORCEPROP 1 LAST VALUE 0
J 2
(-9675 9125);
DISPLAY 0.638298 (-9675 9125);
FORCEPROP 1 LAST WATTAGE 1/16W
J 2
(-9575 9250);
DISPLAY 0.638298 (-9575 9250);
DISPLAY INVISIBLE (-9575 9250);
FORCEPROP 1 LAST TOLERANCE 5%
J 0
(-9650 9125);
DISPLAY 0.638298 (-9650 9125);
DISPLAY INVISIBLE (-9650 9125);
FORCEPROP 1 LAST PACK_TYPE 0402LF
J 0
(-9950 9250);
DISPLAY 0.638298 (-9950 9250);
DISPLAY INVISIBLE (-9950 9250);
FORCEPROP 2 LAST CDS_LIB pure_quanta
J 0
(-9825 9125);
DISPLAY INVISIBLE (-9825 9125);
FORCEPROP 1 LAST PATH I177
J 0
(-9875 9275);
DISPLAY 0.978723 (-9875 9275);
PAINT WHITE (-9875 9275);
DISPLAY INVISIBLE (-9875 9275);
FORCEPROP 1 LAST PART_NUMBER CS00002JB13
J 0
(-9950 9200);
DISPLAY 0.638298 (-9950 9200);
DISPLAY INVISIBLE (-9950 9200);
FORCEADD Q_RES..1
(-9825 9075);
FORCEPROP 1 LAST LOCATION R6065
J 0
(-10025 9075);
DISPLAY 0.638298 (-10025 9075);
FORCEPROP 0 LAST $SEC 1
J 0
(-9575 9125);
DISPLAY 0.680851 (-9575 9125);
PAINT MONO (-9575 9125);
DISPLAY INVISIBLE (-9575 9125);
FORCEPROP 0 LAST CDS_SEC 1
J 0
(-9575 9125);
DISPLAY 1.021277 (-9575 9125);
DISPLAY INVISIBLE (-9575 9125);
FORCEPROP 1 LASTPIN (-9925 9075) $PN 1
J 0
(-9913 9087);
DISPLAY 0.787234 (-9913 9087);
PAINT MONO (-9913 9087);
FORCEPROP 1 LASTPIN (-9725 9075) $PN 2
J 0
(-9763 9087);
DISPLAY 0.787234 (-9763 9087);
PAINT MONO (-9763 9087);
FORCEPROP 1 LAST MATERIAL EMPTY
J 0
(-9575 9075);
DISPLAY 0.638298 (-9575 9075);
FORCEPROP 1 LAST VALUE 0
J 2
(-9675 9075);
DISPLAY 0.638298 (-9675 9075);
FORCEPROP 2 LAST CDS_LIB pure_quanta
J 0
(-9825 9075);
DISPLAY INVISIBLE (-9825 9075);
FORCEPROP 1 LAST PACK_TYPE 0402LF
J 0
(-9950 9200);
DISPLAY 0.638298 (-9950 9200);
DISPLAY INVISIBLE (-9950 9200);
FORCEPROP 1 LAST TOLERANCE 5%
J 0
(-9650 9075);
DISPLAY 0.638298 (-9650 9075);
DISPLAY INVISIBLE (-9650 9075);
FORCEPROP 1 LAST WATTAGE 1/16W
J 2
(-9575 9200);
DISPLAY 0.638298 (-9575 9200);
DISPLAY INVISIBLE (-9575 9200);
FORCEPROP 1 LAST PATH I178
J 0
(-9875 9225);
DISPLAY 0.978723 (-9875 9225);
PAINT WHITE (-9875 9225);
DISPLAY INVISIBLE (-9875 9225);
FORCEPROP 1 LAST PART_NUMBER CS00002JB13
J 0
(-9950 9150);
DISPLAY 0.638298 (-9950 9150);
DISPLAY INVISIBLE (-9950 9150);
FORCEADD OFFPAGE..2
(-8325 9125);
FORCEPROP 2 LAST $XR1 164 
J 0
(-8016 9125);
DISPLAY 0.638298 (-8016 9125);
PAINT MONO (-8016 9125);
FORCEPROP 2 LAST $XR0 151 
J 0
(-8136 9125);
DISPLAY 0.638298 (-8136 9125);
PAINT MONO (-8136 9125);
FORCEPROP 2 LAST CDS_LIB standard
J 0
(-8325 9125);
DISPLAY INVISIBLE (-8325 9125);
FORCEPROP 1 LAST OFFPAGE TRUE
J 0
(-8000 9000);
DISPLAY 0.872340 (-8000 9000);
PAINT GREEN (-8000 9000);
DISPLAY INVISIBLE (-8000 9000);
FORCEPROP 1 LAST COMMENT_BODY TRUE
J 0
(-8370 9030);
DISPLAY 0.872340 (-8370 9030);
PAINT PEACH (-8370 9030);
DISPLAY INVISIBLE (-8370 9030);
FORCEPROP 2 LAST PATH I179
J 0
(-8150 9200);
DISPLAY 0.680851 (-8150 9200);
DISPLAY INVISIBLE (-8150 9200);
FORCEADD Q_RES..2
(-15200 4700);
FORCEPROP 1 LAST LOCATION R6034
J 0
(-15155 4825);
DISPLAY 0.978723 (-15155 4825);
FORCEPROP 0 LAST $SEC 1
J 0
(-15150 4875);
DISPLAY 0.680851 (-15150 4875);
PAINT MONO (-15150 4875);
DISPLAY INVISIBLE (-15150 4875);
FORCEPROP 0 LAST CDS_SEC 1
J 0
(-15075 4725);
DISPLAY 0.680851 (-15075 4725);
DISPLAY INVISIBLE (-15075 4725);
FORCEPROP 1 LASTPIN (-15200 4800) $PN 1
J 0
(-15195 4762);
DISPLAY 0.787234 (-15195 4762);
PAINT MONO (-15195 4762);
FORCEPROP 1 LASTPIN (-15200 4600) $PN 2
J 0
(-15195 4610);
DISPLAY 0.787234 (-15195 4610);
PAINT MONO (-15195 4610);
FORCEPROP 1 LAST PACK_TYPE 0402LF
J 0
(-15160 4525);
DISPLAY 0.978723 (-15160 4525);
FORCEPROP 1 LAST MATERIAL CHIP
J 0
(-15160 4625);
DISPLAY 0.978723 (-15160 4625);
FORCEPROP 1 LAST WATTAGE 1/16W
J 0
(-15160 4675);
DISPLAY 0.978723 (-15160 4675);
FORCEPROP 1 LAST VALUE 1K
J 0
(-15155 4775);
DISPLAY 0.978723 (-15155 4775);
FORCEPROP 1 LAST TOLERANCE 1%
J 0
(-15155 4725);
DISPLAY 0.978723 (-15155 4725);
FORCEPROP 2 LAST CDS_LIB pure_quanta
J 0
(-15200 4700);
DISPLAY INVISIBLE (-15200 4700);
FORCEPROP 1 LAST PATH I18
J 0
(-15150 4875);
DISPLAY 0.978723 (-15150 4875);
PAINT WHITE (-15150 4875);
DISPLAY INVISIBLE (-15150 4875);
FORCEPROP 1 LAST PART_NUMBER CS21002FB06
J 0
(-15160 4575);
DISPLAY 0.978723 (-15160 4575);
DISPLAY INVISIBLE (-15160 4575);
FORCEADD OFFPAGE..1
R 2
(-8325 9075);
FORCEPROP 2 LAST $XR1 151 
J 0
(-8019 9075);
DISPLAY 0.638298 (-8019 9075);
PAINT MONO (-8019 9075);
FORCEPROP 2 LAST $XR0 164 
J 0
(-8139 9075);
DISPLAY 0.638298 (-8139 9075);
PAINT MONO (-8139 9075);
FORCEPROP 2 LAST CDS_LIB standard
J 2
(-8325 9075);
DISPLAY INVISIBLE (-8325 9075);
FORCEPROP 1 LAST OFFPAGE TRUE
J 2
(-8650 8950);
DISPLAY 0.872340 (-8650 8950);
DISPLAY INVISIBLE (-8650 8950);
FORCEPROP 1 LAST COMMENT_BODY TRUE
J 2
(-8450 8975);
DISPLAY 0.872340 (-8450 8975);
PAINT GREEN (-8450 8975);
DISPLAY INVISIBLE (-8450 8975);
FORCEPROP 2 LAST PATH I180
J 2
(-8500 9150);
DISPLAY 0.680851 (-8500 9150);
DISPLAY INVISIBLE (-8500 9150);
FORCEADD VCC_CORE..1
(-16775 6600);
FORCEPROP 3 LASTPIN (-16775 6550) SIG_NAME P3V3_AUX\g
J 0
(-16765 6560);
DISPLAY 0.659574 (-16765 6560);
PAINT MONO (-16765 6560);
DISPLAY INVISIBLE (-16765 6560);
FORCEPROP 1 LAST HDL_POWER P3V3_AUX
J 1
(-16775 6650);
DISPLAY 0.489362 (-16775 6650);
PAINT GREEN (-16775 6650);
FORCEPROP 2 LAST CDS_LIB pure_quanta_power
J 0
(-16775 6600);
DISPLAY INVISIBLE (-16775 6600);
FORCEPROP 1 LAST PATH I182
J 0
(-16725 6625);
DISPLAY 0.872340 (-16725 6625);
PAINT AQUA (-16725 6625);
DISPLAY INVISIBLE (-16725 6625);
FORCEADD OFFPAGE..3
(-10000 8875);
FORCEPROP 2 LAST $XR0 80 
J 0
(-9786 8875);
DISPLAY 0.638298 (-9786 8875);
PAINT MONO (-9786 8875);
FORCEPROP 2 LAST CDS_LIB standard
J 0
(-10000 8875);
PAINT MONO (-10000 8875);
DISPLAY INVISIBLE (-10000 8875);
FORCEPROP 1 LAST OFFPAGE TRUE
J 0
(-9675 8750);
DISPLAY 0.872340 (-9675 8750);
DISPLAY INVISIBLE (-9675 8750);
FORCEPROP 1 LAST COMMENT_BODY TRUE
J 0
(-10050 8775);
DISPLAY 0.872340 (-10050 8775);
PAINT GREEN (-10050 8775);
DISPLAY INVISIBLE (-10050 8775);
FORCEPROP 2 LAST PATH I185
J 0
(-9800 8950);
DISPLAY 0.680851 (-9800 8950);
DISPLAY INVISIBLE (-9800 8950);
FORCEADD UNIVERSAL_POWER..1
(-15200 4975);
FORCEPROP 3 LASTPIN (-15200 4925) SIG_NAME P3V3_AUX\g
J 0
(-15190 4935);
DISPLAY 0.659574 (-15190 4935);
PAINT MONO (-15190 4935);
DISPLAY INVISIBLE (-15190 4935);
FORCEPROP 1 LAST HDL_POWER P3V3_AUX
J 1
(-15200 5025);
DISPLAY 0.702128 (-15200 5025);
PAINT GREEN (-15200 5025);
FORCEPROP 2 LAST CDS_LIB pure_quanta_power
J 0
(-15200 4975);
DISPLAY INVISIBLE (-15200 4975);
FORCEPROP 1 LAST PATH I19
J 0
(-15150 5000);
DISPLAY 0.872340 (-15150 5000);
PAINT AQUA (-15150 5000);
DISPLAY INVISIBLE (-15150 5000);
FORCEADD Q_RES..1
(-14925 8325);
FORCEPROP 1 LAST LOCATION R4507
J 0
(-15150 8325);
DISPLAY 0.638298 (-15150 8325);
FORCEPROP 0 LAST $SEC 1
J 0
(-15125 8375);
DISPLAY 0.680851 (-15125 8375);
PAINT MONO (-15125 8375);
DISPLAY INVISIBLE (-15125 8375);
FORCEPROP 0 LAST CDS_SEC 1
J 0
(-15125 8375);
DISPLAY 1.021277 (-15125 8375);
DISPLAY INVISIBLE (-15125 8375);
FORCEPROP 1 LASTPIN (-15025 8325) $PN 1
J 0
(-15013 8337);
DISPLAY 0.787234 (-15013 8337);
PAINT MONO (-15013 8337);
FORCEPROP 1 LASTPIN (-14825 8325) $PN 2
J 0
(-14863 8337);
DISPLAY 0.787234 (-14863 8337);
PAINT MONO (-14863 8337);
FORCEPROP 1 LAST MATERIAL CHIP
J 0
(-14625 8325);
DISPLAY 0.510638 (-14625 8325);
FORCEPROP 1 LAST TOLERANCE 1%
J 0
(-14700 8325);
DISPLAY 0.510638 (-14700 8325);
FORCEPROP 1 LAST VALUE 33.2
J 2
(-14725 8325);
DISPLAY 0.510638 (-14725 8325);
FORCEPROP 1 LAST WATTAGE 1/16W
J 2
(-14825 8425);
DISPLAY 0.404255 (-14825 8425);
DISPLAY INVISIBLE (-14825 8425);
FORCEPROP 1 LAST PACK_TYPE 0402LF
J 0
(-15050 8425);
DISPLAY 0.404255 (-15050 8425);
DISPLAY INVISIBLE (-15050 8425);
FORCEPROP 2 LAST CDS_LIB pure_quanta
J 0
(-14925 8325);
DISPLAY INVISIBLE (-14925 8325);
FORCEPROP 1 LAST PATH I190
J 0
(-14975 8475);
DISPLAY 0.978723 (-14975 8475);
PAINT WHITE (-14975 8475);
DISPLAY INVISIBLE (-14975 8475);
FORCEPROP 1 LAST PART_NUMBER CS03322FB03
J 0
(-15050 8375);
DISPLAY 0.404255 (-15050 8375);
DISPLAY INVISIBLE (-15050 8375);
FORCEADD Q_RES..1
(-14925 8375);
FORCEPROP 1 LAST LOCATION R4506
J 0
(-15150 8375);
DISPLAY 0.638298 (-15150 8375);
FORCEPROP 0 LAST $SEC 1
J 0
(-15125 8425);
DISPLAY 0.680851 (-15125 8425);
PAINT MONO (-15125 8425);
DISPLAY INVISIBLE (-15125 8425);
FORCEPROP 0 LAST CDS_SEC 1
J 0
(-15125 8425);
DISPLAY 1.021277 (-15125 8425);
DISPLAY INVISIBLE (-15125 8425);
FORCEPROP 1 LASTPIN (-15025 8375) $PN 1
J 0
(-15013 8387);
DISPLAY 0.787234 (-15013 8387);
PAINT MONO (-15013 8387);
FORCEPROP 1 LASTPIN (-14825 8375) $PN 2
J 0
(-14863 8387);
DISPLAY 0.787234 (-14863 8387);
PAINT MONO (-14863 8387);
FORCEPROP 1 LAST MATERIAL CHIP
J 0
(-14625 8375);
DISPLAY 0.510638 (-14625 8375);
FORCEPROP 1 LAST TOLERANCE 1%
J 0
(-14700 8375);
DISPLAY 0.510638 (-14700 8375);
FORCEPROP 1 LAST VALUE 33.2
J 2
(-14725 8375);
DISPLAY 0.510638 (-14725 8375);
FORCEPROP 1 LAST WATTAGE 1/16W
J 2
(-14825 8475);
DISPLAY 0.404255 (-14825 8475);
DISPLAY INVISIBLE (-14825 8475);
FORCEPROP 1 LAST PACK_TYPE 0402LF
J 0
(-15050 8475);
DISPLAY 0.404255 (-15050 8475);
DISPLAY INVISIBLE (-15050 8475);
FORCEPROP 2 LAST CDS_LIB pure_quanta
J 0
(-14925 8375);
DISPLAY INVISIBLE (-14925 8375);
FORCEPROP 1 LAST PATH I191
J 0
(-14975 8525);
DISPLAY 0.978723 (-14975 8525);
PAINT WHITE (-14975 8525);
DISPLAY INVISIBLE (-14975 8525);
FORCEPROP 1 LAST PART_NUMBER CS03322FB03
J 0
(-15050 8425);
DISPLAY 0.404255 (-15050 8425);
DISPLAY INVISIBLE (-15050 8425);
FORCEADD OFFPAGE..6
(-16225 8325);
FORCEPROP 2 LAST $XR1 160 
J 0
(-16625 8325);
DISPLAY 0.638298 (-16625 8325);
PAINT MONO (-16625 8325);
FORCEPROP 2 LAST $XR0 151 
J 0
(-16505 8325);
DISPLAY 0.638298 (-16505 8325);
PAINT MONO (-16505 8325);
FORCEPROP 2 LAST CDS_LIB standard
J 0
(-16225 8325);
DISPLAY INVISIBLE (-16225 8325);
FORCEPROP 1 LAST OFFPAGE TRUE
J 0
(-15900 8200);
DISPLAY 0.872340 (-15900 8200);
PAINT GREEN (-15900 8200);
DISPLAY INVISIBLE (-15900 8200);
FORCEPROP 1 LAST COMMENT_BODY TRUE
J 0
(-16125 8250);
DISPLAY 0.872340 (-16125 8250);
PAINT PEACH (-16125 8250);
DISPLAY INVISIBLE (-16125 8250);
FORCEPROP 2 LAST PATH I192
J 0
(-16500 8375);
DISPLAY 0.680851 (-16500 8375);
DISPLAY INVISIBLE (-16500 8375);
FORCEADD Q_RES..1
(-14925 7425);
FORCEPROP 1 LAST LOCATION R2424
J 0
(-15150 7425);
DISPLAY 0.638298 (-15150 7425);
FORCEPROP 0 LAST $SEC 1
J 0
(-15150 7475);
DISPLAY 0.680851 (-15150 7475);
PAINT MONO (-15150 7475);
DISPLAY INVISIBLE (-15150 7475);
FORCEPROP 0 LAST CDS_SEC 1
J 0
(-15150 7475);
DISPLAY 1.021277 (-15150 7475);
DISPLAY INVISIBLE (-15150 7475);
FORCEPROP 1 LASTPIN (-15025 7425) $PN 1
J 0
(-15013 7437);
DISPLAY 0.787234 (-15013 7437);
PAINT MONO (-15013 7437);
FORCEPROP 1 LASTPIN (-14825 7425) $PN 2
J 0
(-14863 7437);
DISPLAY 0.787234 (-14863 7437);
PAINT MONO (-14863 7437);
FORCEPROP 1 LAST MATERIAL CHIP
J 0
(-14625 7425);
DISPLAY 0.510638 (-14625 7425);
FORCEPROP 1 LAST TOLERANCE 1%
J 0
(-14700 7425);
DISPLAY 0.510638 (-14700 7425);
FORCEPROP 1 LAST VALUE 33.2
J 2
(-14725 7425);
DISPLAY 0.510638 (-14725 7425);
FORCEPROP 1 LAST PACK_TYPE 0402LF
J 0
(-15050 7525);
DISPLAY 0.404255 (-15050 7525);
DISPLAY INVISIBLE (-15050 7525);
FORCEPROP 1 LAST WATTAGE 1/16W
J 2
(-14825 7525);
DISPLAY 0.404255 (-14825 7525);
DISPLAY INVISIBLE (-14825 7525);
FORCEPROP 2 LAST CDS_LIB pure_quanta
J 0
(-14925 7425);
DISPLAY INVISIBLE (-14925 7425);
FORCEPROP 1 LAST PATH I195
J 0
(-14975 7575);
DISPLAY 0.978723 (-14975 7575);
PAINT WHITE (-14975 7575);
DISPLAY INVISIBLE (-14975 7575);
FORCEPROP 1 LAST PART_NUMBER CS03322FB03
J 0
(-15050 7475);
DISPLAY 0.404255 (-15050 7475);
DISPLAY INVISIBLE (-15050 7475);
FORCEADD Q_RES..1
(-14925 7475);
FORCEPROP 1 LAST LOCATION R2423
J 0
(-15150 7475);
DISPLAY 0.638298 (-15150 7475);
FORCEPROP 0 LAST $SEC 1
J 0
(-15150 7525);
DISPLAY 0.680851 (-15150 7525);
PAINT MONO (-15150 7525);
DISPLAY INVISIBLE (-15150 7525);
FORCEPROP 0 LAST CDS_SEC 1
J 0
(-15150 7525);
DISPLAY 1.021277 (-15150 7525);
DISPLAY INVISIBLE (-15150 7525);
FORCEPROP 1 LASTPIN (-15025 7475) $PN 1
J 0
(-15013 7487);
DISPLAY 0.787234 (-15013 7487);
PAINT MONO (-15013 7487);
FORCEPROP 1 LASTPIN (-14825 7475) $PN 2
J 0
(-14863 7487);
DISPLAY 0.787234 (-14863 7487);
PAINT MONO (-14863 7487);
FORCEPROP 1 LAST VALUE 33.2
J 2
(-14725 7475);
DISPLAY 0.510638 (-14725 7475);
FORCEPROP 1 LAST TOLERANCE 1%
J 0
(-14700 7475);
DISPLAY 0.510638 (-14700 7475);
FORCEPROP 1 LAST MATERIAL CHIP
J 0
(-14625 7475);
DISPLAY 0.510638 (-14625 7475);
FORCEPROP 1 LAST PACK_TYPE 0402LF
J 0
(-15050 7575);
DISPLAY 0.404255 (-15050 7575);
DISPLAY INVISIBLE (-15050 7575);
FORCEPROP 1 LAST WATTAGE 1/16W
J 2
(-14825 7575);
DISPLAY 0.404255 (-14825 7575);
DISPLAY INVISIBLE (-14825 7575);
FORCEPROP 2 LAST CDS_LIB pure_quanta
J 0
(-14925 7475);
DISPLAY INVISIBLE (-14925 7475);
FORCEPROP 1 LAST PATH I196
J 0
(-14975 7625);
DISPLAY 0.978723 (-14975 7625);
PAINT WHITE (-14975 7625);
DISPLAY INVISIBLE (-14975 7625);
FORCEPROP 1 LAST PART_NUMBER CS03322FB03
J 0
(-15050 7525);
DISPLAY 0.404255 (-15050 7525);
DISPLAY INVISIBLE (-15050 7525);
FORCEADD OFFPAGE..6
(-16200 7425);
FORCEPROP 2 LAST $XR0 151 
J 0
(-16480 7425);
DISPLAY 0.638298 (-16480 7425);
PAINT MONO (-16480 7425);
FORCEPROP 2 LAST CDS_LIB standard
J 0
(-16200 7425);
DISPLAY INVISIBLE (-16200 7425);
FORCEPROP 1 LAST OFFPAGE TRUE
J 0
(-15875 7300);
DISPLAY 0.872340 (-15875 7300);
PAINT GREEN (-15875 7300);
DISPLAY INVISIBLE (-15875 7300);
FORCEPROP 1 LAST COMMENT_BODY TRUE
J 0
(-16100 7350);
DISPLAY 0.872340 (-16100 7350);
PAINT PEACH (-16100 7350);
DISPLAY INVISIBLE (-16100 7350);
FORCEPROP 2 LAST PATH I197
J 0
(-16475 7475);
DISPLAY 0.680851 (-16475 7475);
DISPLAY INVISIBLE (-16475 7475);
FORCEADD OFFPAGE..2
R 2
(-16250 8375);
FORCEPROP 2 LAST $XR1 160 
J 0
(-16625 8375);
DISPLAY 0.638298 (-16625 8375);
PAINT MONO (-16625 8375);
FORCEPROP 2 LAST $XR0 151 
J 0
(-16505 8375);
DISPLAY 0.638298 (-16505 8375);
PAINT MONO (-16505 8375);
FORCEPROP 2 LAST CDS_LIB standard
J 0
(-16250 8375);
DISPLAY INVISIBLE (-16250 8375);
FORCEPROP 1 LAST OFFPAGE TRUE
J 2
(-16575 8250);
DISPLAY 0.872340 (-16575 8250);
DISPLAY INVISIBLE (-16575 8250);
FORCEPROP 1 LAST COMMENT_BODY TRUE
J 2
(-16205 8280);
DISPLAY 0.872340 (-16205 8280);
PAINT GREEN (-16205 8280);
DISPLAY INVISIBLE (-16205 8280);
FORCEPROP 2 LAST PATH I198
J 0
(-16200 8450);
DISPLAY 0.680851 (-16200 8450);
DISPLAY INVISIBLE (-16200 8450);
FORCEADD OFFPAGE..2
R 2
(-16250 8475);
FORCEPROP 2 LAST $XR0 253 
J 0
(-16505 8475);
DISPLAY 0.638298 (-16505 8475);
PAINT MONO (-16505 8475);
FORCEPROP 2 LAST CDS_LIB standard
J 0
(-16250 8475);
DISPLAY INVISIBLE (-16250 8475);
FORCEPROP 1 LAST OFFPAGE TRUE
J 2
(-16575 8350);
DISPLAY 0.872340 (-16575 8350);
DISPLAY INVISIBLE (-16575 8350);
FORCEPROP 1 LAST COMMENT_BODY TRUE
J 2
(-16205 8380);
DISPLAY 0.872340 (-16205 8380);
PAINT GREEN (-16205 8380);
DISPLAY INVISIBLE (-16205 8380);
FORCEPROP 2 LAST PATH I199
J 0
(-16200 8550);
DISPLAY 0.680851 (-16200 8550);
DISPLAY INVISIBLE (-16200 8550);
FORCEADD OFFPAGE..1
(-16225 5725);
FORCEPROP 2 LAST $XR0 84 
J 0
(-16446 5725);
DISPLAY 0.638298 (-16446 5725);
PAINT MONO (-16446 5725);
FORCEPROP 2 LAST CDS_LIB standard
J 0
(-16225 5725);
DISPLAY INVISIBLE (-16225 5725);
FORCEPROP 1 LAST OFFPAGE TRUE
J 0
(-15900 5600);
DISPLAY 0.872340 (-15900 5600);
PAINT GREEN (-15900 5600);
DISPLAY INVISIBLE (-15900 5600);
FORCEPROP 1 LAST COMMENT_BODY TRUE
J 0
(-16100 5625);
DISPLAY 0.872340 (-16100 5625);
PAINT PEACH (-16100 5625);
DISPLAY INVISIBLE (-16100 5625);
FORCEPROP 2 LAST PATH I2
J 0
(-16175 5800);
DISPLAY 0.680851 (-16175 5800);
DISPLAY INVISIBLE (-16175 5800);
FORCEADD OFFPAGE..1
(-14100 5275);
FORCEPROP 2 LAST $XR0 113 
J 0
(-14352 5275);
DISPLAY 0.638298 (-14352 5275);
PAINT MONO (-14352 5275);
FORCEPROP 2 LAST CDS_LIB standard
J 0
(-14100 5275);
DISPLAY INVISIBLE (-14100 5275);
FORCEPROP 1 LAST OFFPAGE TRUE
J 0
(-13775 5150);
DISPLAY 0.872340 (-13775 5150);
PAINT GREEN (-13775 5150);
DISPLAY INVISIBLE (-13775 5150);
FORCEPROP 1 LAST COMMENT_BODY TRUE
J 0
(-13975 5175);
DISPLAY 0.872340 (-13975 5175);
PAINT PEACH (-13975 5175);
DISPLAY INVISIBLE (-13975 5175);
FORCEPROP 2 LAST PATH I20
J 0
(-14050 5350);
DISPLAY 0.680851 (-14050 5350);
DISPLAY INVISIBLE (-14050 5350);
FORCEADD OFFPAGE..2
R 2
(-16250 8575);
FORCEPROP 2 LAST $XR1 160 
J 0
(-16625 8575);
DISPLAY 0.638298 (-16625 8575);
PAINT MONO (-16625 8575);
FORCEPROP 2 LAST $XR0 151 
J 0
(-16505 8575);
DISPLAY 0.638298 (-16505 8575);
PAINT MONO (-16505 8575);
FORCEPROP 2 LAST CDS_LIB standard
J 0
(-16250 8575);
DISPLAY INVISIBLE (-16250 8575);
FORCEPROP 1 LAST OFFPAGE TRUE
J 2
(-16575 8450);
DISPLAY 0.872340 (-16575 8450);
DISPLAY INVISIBLE (-16575 8450);
FORCEPROP 1 LAST COMMENT_BODY TRUE
J 2
(-16205 8480);
DISPLAY 0.872340 (-16205 8480);
PAINT GREEN (-16205 8480);
DISPLAY INVISIBLE (-16205 8480);
FORCEPROP 2 LAST PATH I200
J 0
(-16200 8650);
DISPLAY 0.680851 (-16200 8650);
DISPLAY INVISIBLE (-16200 8650);
FORCEADD OFFPAGE..2
R 2
(-16250 8675);
FORCEPROP 2 LAST $XR1 248 
J 0
(-16625 8675);
DISPLAY 0.638298 (-16625 8675);
PAINT MONO (-16625 8675);
FORCEPROP 2 LAST $XR0 151 
J 0
(-16505 8675);
DISPLAY 0.638298 (-16505 8675);
PAINT MONO (-16505 8675);
FORCEPROP 2 LAST CDS_LIB standard
J 0
(-16250 8675);
DISPLAY INVISIBLE (-16250 8675);
FORCEPROP 1 LAST OFFPAGE TRUE
J 2
(-16575 8550);
DISPLAY 0.872340 (-16575 8550);
DISPLAY INVISIBLE (-16575 8550);
FORCEPROP 1 LAST COMMENT_BODY TRUE
J 2
(-16205 8580);
DISPLAY 0.872340 (-16205 8580);
PAINT GREEN (-16205 8580);
DISPLAY INVISIBLE (-16205 8580);
FORCEPROP 2 LAST PATH I201
J 0
(-16200 8750);
DISPLAY 0.680851 (-16200 8750);
DISPLAY INVISIBLE (-16200 8750);
FORCEADD OFFPAGE..2
R 2
(-15625 9275);
FORCEPROP 2 LAST $XR0 159 
J 0
(-15910 9275);
DISPLAY 0.638298 (-15910 9275);
PAINT MONO (-15910 9275);
FORCEPROP 2 LAST CDS_LIB standard
J 0
(-15625 9275);
DISPLAY INVISIBLE (-15625 9275);
FORCEPROP 1 LAST OFFPAGE TRUE
J 2
(-15950 9150);
DISPLAY 0.872340 (-15950 9150);
DISPLAY INVISIBLE (-15950 9150);
FORCEPROP 1 LAST COMMENT_BODY TRUE
J 2
(-15580 9180);
DISPLAY 0.872340 (-15580 9180);
PAINT GREEN (-15580 9180);
DISPLAY INVISIBLE (-15580 9180);
FORCEPROP 2 LAST PATH I202
J 0
(-15575 9350);
DISPLAY 0.680851 (-15575 9350);
DISPLAY INVISIBLE (-15575 9350);
FORCEADD OFFPAGE..2
R 2
(-15625 9175);
FORCEPROP 2 LAST $XR0 159 
J 0
(-15910 9175);
DISPLAY 0.638298 (-15910 9175);
PAINT MONO (-15910 9175);
FORCEPROP 2 LAST CDS_LIB standard
J 0
(-15625 9175);
DISPLAY INVISIBLE (-15625 9175);
FORCEPROP 1 LAST OFFPAGE TRUE
J 2
(-15950 9050);
DISPLAY 0.872340 (-15950 9050);
DISPLAY INVISIBLE (-15950 9050);
FORCEPROP 1 LAST COMMENT_BODY TRUE
J 2
(-15580 9080);
DISPLAY 0.872340 (-15580 9080);
PAINT GREEN (-15580 9080);
DISPLAY INVISIBLE (-15580 9080);
FORCEPROP 2 LAST PATH I203
J 0
(-15575 9250);
DISPLAY 0.680851 (-15575 9250);
DISPLAY INVISIBLE (-15575 9250);
FORCEADD OFFPAGE..2
R 2
(-15625 9075);
FORCEPROP 2 LAST $XR0 159 
J 0
(-15910 9075);
DISPLAY 0.638298 (-15910 9075);
PAINT MONO (-15910 9075);
FORCEPROP 2 LAST CDS_LIB standard
J 0
(-15625 9075);
DISPLAY INVISIBLE (-15625 9075);
FORCEPROP 1 LAST OFFPAGE TRUE
J 2
(-15950 8950);
DISPLAY 0.872340 (-15950 8950);
DISPLAY INVISIBLE (-15950 8950);
FORCEPROP 1 LAST COMMENT_BODY TRUE
J 2
(-15580 8980);
DISPLAY 0.872340 (-15580 8980);
PAINT GREEN (-15580 8980);
DISPLAY INVISIBLE (-15580 8980);
FORCEPROP 2 LAST PATH I204
J 0
(-15575 9150);
DISPLAY 0.680851 (-15575 9150);
DISPLAY INVISIBLE (-15575 9150);
FORCEADD OFFPAGE..2
R 2
(-15625 8975);
FORCEPROP 2 LAST $XR0 159 
J 0
(-15910 8975);
DISPLAY 0.638298 (-15910 8975);
PAINT MONO (-15910 8975);
FORCEPROP 2 LAST CDS_LIB standard
J 0
(-15625 8975);
DISPLAY INVISIBLE (-15625 8975);
FORCEPROP 1 LAST OFFPAGE TRUE
J 2
(-15950 8850);
DISPLAY 0.872340 (-15950 8850);
DISPLAY INVISIBLE (-15950 8850);
FORCEPROP 1 LAST COMMENT_BODY TRUE
J 2
(-15580 8880);
DISPLAY 0.872340 (-15580 8880);
PAINT GREEN (-15580 8880);
DISPLAY INVISIBLE (-15580 8880);
FORCEPROP 2 LAST PATH I205
J 0
(-15575 9050);
DISPLAY 0.680851 (-15575 9050);
DISPLAY INVISIBLE (-15575 9050);
FORCEADD OFFPAGE..2
R 2
(-16225 7475);
FORCEPROP 2 LAST $XR0 151 
J 0
(-16480 7475);
DISPLAY 0.638298 (-16480 7475);
PAINT MONO (-16480 7475);
FORCEPROP 2 LAST CDS_LIB standard
J 0
(-16225 7475);
DISPLAY INVISIBLE (-16225 7475);
FORCEPROP 1 LAST OFFPAGE TRUE
J 2
(-16550 7350);
DISPLAY 0.872340 (-16550 7350);
DISPLAY INVISIBLE (-16550 7350);
FORCEPROP 1 LAST COMMENT_BODY TRUE
J 2
(-16180 7380);
DISPLAY 0.872340 (-16180 7380);
PAINT GREEN (-16180 7380);
DISPLAY INVISIBLE (-16180 7380);
FORCEPROP 2 LAST PATH I206
J 0
(-16175 7550);
DISPLAY 0.680851 (-16175 7550);
DISPLAY INVISIBLE (-16175 7550);
FORCEADD OFFPAGE..2
R 2
(-16225 7075);
FORCEPROP 2 LAST $XR1 249 
J 0
(-16600 7075);
DISPLAY 0.638298 (-16600 7075);
PAINT MONO (-16600 7075);
FORCEPROP 2 LAST $XR0 151 
J 0
(-16480 7075);
DISPLAY 0.638298 (-16480 7075);
PAINT MONO (-16480 7075);
FORCEPROP 2 LAST CDS_LIB standard
J 0
(-16225 7075);
DISPLAY INVISIBLE (-16225 7075);
FORCEPROP 1 LAST OFFPAGE TRUE
J 2
(-16550 6950);
DISPLAY 0.872340 (-16550 6950);
DISPLAY INVISIBLE (-16550 6950);
FORCEPROP 1 LAST COMMENT_BODY TRUE
J 2
(-16180 6980);
DISPLAY 0.872340 (-16180 6980);
PAINT GREEN (-16180 6980);
DISPLAY INVISIBLE (-16180 6980);
FORCEPROP 2 LAST PATH I207
J 0
(-16175 7150);
DISPLAY 0.680851 (-16175 7150);
DISPLAY INVISIBLE (-16175 7150);
FORCEADD OFFPAGE..2
R 2
(-16225 6725);
FORCEPROP 2 LAST $XR0 151 
J 0
(-16480 6725);
DISPLAY 0.638298 (-16480 6725);
PAINT MONO (-16480 6725);
FORCEPROP 2 LAST $XR1 249 
J 0
(-16600 6725);
DISPLAY 0.638298 (-16600 6725);
PAINT MONO (-16600 6725);
FORCEPROP 2 LAST CDS_LIB standard
J 0
(-16225 6725);
DISPLAY INVISIBLE (-16225 6725);
FORCEPROP 1 LAST OFFPAGE TRUE
J 2
(-16550 6600);
DISPLAY 0.872340 (-16550 6600);
DISPLAY INVISIBLE (-16550 6600);
FORCEPROP 1 LAST COMMENT_BODY TRUE
J 2
(-16180 6630);
DISPLAY 0.872340 (-16180 6630);
PAINT GREEN (-16180 6630);
DISPLAY INVISIBLE (-16180 6630);
FORCEPROP 2 LAST PATH I208
J 0
(-16175 6800);
DISPLAY 0.680851 (-16175 6800);
DISPLAY INVISIBLE (-16175 6800);
FORCEADD OFFPAGE..2
R 2
(-16225 6625);
FORCEPROP 2 LAST $XR0 151 
J 0
(-16480 6625);
DISPLAY 0.638298 (-16480 6625);
PAINT MONO (-16480 6625);
FORCEPROP 2 LAST CDS_LIB standard
J 0
(-16225 6625);
DISPLAY INVISIBLE (-16225 6625);
FORCEPROP 1 LAST OFFPAGE TRUE
J 2
(-16550 6500);
DISPLAY 0.872340 (-16550 6500);
DISPLAY INVISIBLE (-16550 6500);
FORCEPROP 1 LAST COMMENT_BODY TRUE
J 2
(-16180 6530);
DISPLAY 0.872340 (-16180 6530);
PAINT GREEN (-16180 6530);
DISPLAY INVISIBLE (-16180 6530);
FORCEPROP 2 LAST PATH I209
J 0
(-16175 6700);
DISPLAY 0.680851 (-16175 6700);
DISPLAY INVISIBLE (-16175 6700);
FORCEADD OFFPAGE..1
(-14100 5225);
FORCEPROP 2 LAST $XR0 113 
J 0
(-14352 5225);
DISPLAY 0.638298 (-14352 5225);
PAINT MONO (-14352 5225);
FORCEPROP 2 LAST CDS_LIB standard
J 0
(-14100 5225);
DISPLAY INVISIBLE (-14100 5225);
FORCEPROP 1 LAST OFFPAGE TRUE
J 0
(-13775 5100);
DISPLAY 0.872340 (-13775 5100);
PAINT GREEN (-13775 5100);
DISPLAY INVISIBLE (-13775 5100);
FORCEPROP 1 LAST COMMENT_BODY TRUE
J 0
(-13975 5125);
DISPLAY 0.872340 (-13975 5125);
PAINT PEACH (-13975 5125);
DISPLAY INVISIBLE (-13975 5125);
FORCEPROP 2 LAST PATH I21
J 0
(-14050 5300);
DISPLAY 0.680851 (-14050 5300);
DISPLAY INVISIBLE (-14050 5300);
FORCEADD OFFPAGE..2
R 2
(-16225 7375);
FORCEPROP 2 LAST $XR0 151 
J 0
(-16480 7375);
DISPLAY 0.638298 (-16480 7375);
PAINT MONO (-16480 7375);
FORCEPROP 2 LAST CDS_LIB standard
J 0
(-16225 7375);
DISPLAY INVISIBLE (-16225 7375);
FORCEPROP 1 LAST OFFPAGE TRUE
J 2
(-16550 7250);
DISPLAY 0.872340 (-16550 7250);
DISPLAY INVISIBLE (-16550 7250);
FORCEPROP 1 LAST COMMENT_BODY TRUE
J 2
(-16180 7280);
DISPLAY 0.872340 (-16180 7280);
PAINT GREEN (-16180 7280);
DISPLAY INVISIBLE (-16180 7280);
FORCEPROP 2 LAST PATH I210
J 0
(-16175 7450);
DISPLAY 0.680851 (-16175 7450);
DISPLAY INVISIBLE (-16175 7450);
FORCEADD OFFPAGE..2
(-10000 5275);
FORCEPROP 2 LAST $XR0 113 
J 0
(-9811 5275);
DISPLAY 0.638298 (-9811 5275);
PAINT MONO (-9811 5275);
FORCEPROP 2 LAST CDS_LIB standard
J 0
(-10000 5275);
DISPLAY INVISIBLE (-10000 5275);
FORCEPROP 1 LAST OFFPAGE TRUE
J 0
(-9675 5150);
DISPLAY 0.872340 (-9675 5150);
PAINT GREEN (-9675 5150);
DISPLAY INVISIBLE (-9675 5150);
FORCEPROP 1 LAST COMMENT_BODY TRUE
J 0
(-10045 5180);
DISPLAY 0.872340 (-10045 5180);
PAINT PEACH (-10045 5180);
DISPLAY INVISIBLE (-10045 5180);
FORCEPROP 2 LAST PATH I211
J 0
(-9825 5350);
DISPLAY 0.680851 (-9825 5350);
DISPLAY INVISIBLE (-9825 5350);
FORCEADD OFFPAGE..2
(-10000 5225);
FORCEPROP 2 LAST $XR0 113 
J 0
(-9811 5225);
DISPLAY 0.638298 (-9811 5225);
PAINT MONO (-9811 5225);
FORCEPROP 2 LAST CDS_LIB standard
J 0
(-10000 5225);
DISPLAY INVISIBLE (-10000 5225);
FORCEPROP 1 LAST OFFPAGE TRUE
J 0
(-9675 5100);
DISPLAY 0.872340 (-9675 5100);
PAINT GREEN (-9675 5100);
DISPLAY INVISIBLE (-9675 5100);
FORCEPROP 1 LAST COMMENT_BODY TRUE
J 0
(-10045 5130);
DISPLAY 0.872340 (-10045 5130);
PAINT PEACH (-10045 5130);
DISPLAY INVISIBLE (-10045 5130);
FORCEPROP 2 LAST PATH I212
J 0
(-9825 5300);
DISPLAY 0.680851 (-9825 5300);
DISPLAY INVISIBLE (-9825 5300);
FORCEADD OFFPAGE..4
(-10000 8975);
FORCEPROP 2 LAST $XR0 80 
J 0
(-9754 8975);
DISPLAY 0.638298 (-9754 8975);
PAINT MONO (-9754 8975);
FORCEPROP 2 LAST CDS_LIB standard
J 0
(-10000 8975);
DISPLAY INVISIBLE (-10000 8975);
FORCEPROP 1 LAST OFFPAGE TRUE
J 0
(-9675 8850);
DISPLAY 0.872340 (-9675 8850);
PAINT GREEN (-9675 8850);
DISPLAY INVISIBLE (-9675 8850);
FORCEPROP 1 LAST COMMENT_BODY TRUE
J 0
(-10025 8875);
DISPLAY 0.872340 (-10025 8875);
PAINT PEACH (-10025 8875);
DISPLAY INVISIBLE (-10025 8875);
FORCEPROP 2 LAST PATH I213
J 0
(-9825 9050);
DISPLAY 0.680851 (-9825 9050);
DISPLAY INVISIBLE (-9825 9050);
FORCEADD Q_RES..2
R 2
(-16775 6350);
FORCEPROP 1 LAST LOCATION R6071
J 2
(-16820 6475);
DISPLAY 0.638298 (-16820 6475);
FORCEPROP 0 LAST $SEC 1
J 0
(-16800 6525);
DISPLAY 0.680851 (-16800 6525);
PAINT MONO (-16800 6525);
DISPLAY INVISIBLE (-16800 6525);
FORCEPROP 0 LAST CDS_SEC 1
J 0
(-16800 6525);
DISPLAY 0.680851 (-16800 6525);
DISPLAY INVISIBLE (-16800 6525);
FORCEPROP 1 LASTPIN (-16775 6450) $PN 1
J 2
(-16780 6412);
DISPLAY 0.787234 (-16780 6412);
PAINT MONO (-16780 6412);
FORCEPROP 1 LASTPIN (-16775 6250) $PN 2
J 2
(-16780 6260);
DISPLAY 0.787234 (-16780 6260);
PAINT MONO (-16780 6260);
FORCEPROP 1 LAST PACK_TYPE 0402LF
J 2
(-16815 6175);
DISPLAY 0.638298 (-16815 6175);
FORCEPROP 1 LAST MATERIAL EMPTY
J 2
(-16815 6275);
DISPLAY 0.510638 (-16815 6275);
FORCEPROP 1 LAST VALUE 4.7K
J 2
(-16820 6425);
DISPLAY 0.638298 (-16820 6425);
FORCEPROP 1 LAST WATTAGE 1/16W
J 2
(-16815 6325);
DISPLAY 0.638298 (-16815 6325);
FORCEPROP 1 LAST TOLERANCE 5%
J 2
(-16820 6375);
DISPLAY 0.638298 (-16820 6375);
FORCEPROP 2 LAST CDS_LIB pure_quanta
J 2
(-16775 6350);
DISPLAY INVISIBLE (-16775 6350);
FORCEPROP 1 LAST PATH I214
J 2
(-16825 6525);
DISPLAY 0.978723 (-16825 6525);
PAINT WHITE (-16825 6525);
DISPLAY INVISIBLE (-16825 6525);
FORCEPROP 1 LAST PART_NUMBER CS24702JB10
J 2
(-16825 6225);
DISPLAY 0.510638 (-16825 6225);
DISPLAY INVISIBLE (-16825 6225);
FORCEADD Q_RES..1
R 2
(-10300 6525);
FORCEPROP 1 LAST LOCATION R8101
J 2
(-10100 6525);
DISPLAY 0.489362 (-10100 6525);
PAINT SKYBLUE (-10100 6525);
FORCEPROP 0 LAST $SEC 1
J 0
(-10100 6550);
DISPLAY 0.680851 (-10100 6550);
PAINT MONO (-10100 6550);
DISPLAY INVISIBLE (-10100 6550);
FORCEPROP 0 LAST CDS_SEC 1
J 0
(-10100 6550);
DISPLAY 0.680851 (-10100 6550);
DISPLAY INVISIBLE (-10100 6550);
FORCEPROP 1 LASTPIN (-10200 6525) $PN 1
J 2
(-10212 6537);
DISPLAY 0.787234 (-10212 6537);
PAINT MONO (-10212 6537);
FORCEPROP 1 LASTPIN (-10400 6525) $PN 2
J 2
(-10362 6537);
DISPLAY 0.787234 (-10362 6537);
PAINT MONO (-10362 6537);
FORCEPROP 1 LAST VALUE 0
J 0
(-10450 6525);
DISPLAY 0.489362 (-10450 6525);
PAINT SKYBLUE (-10450 6525);
FORCEPROP 2 LAST BOM_COST MEM
J 0
(-10325 6675);
DISPLAY 0.744681 (-10325 6675);
PAINT WHITE (-10325 6675);
DISPLAY INVISIBLE (-10325 6675);
FORCEPROP 1 LAST WATTAGE 1/16W
J 0
(-10225 6450);
DISPLAY 0.489362 (-10225 6450);
PAINT SKYBLUE (-10225 6450);
DISPLAY INVISIBLE (-10225 6450);
FORCEPROP 1 LAST MATERIAL CHIP
J 0
(-10475 6500);
DISPLAY 0.489362 (-10475 6500);
PAINT SKYBLUE (-10475 6500);
DISPLAY INVISIBLE (-10475 6500);
FORCEPROP 1 LAST TOLERANCE 5%
J 2
(-10175 6500);
DISPLAY 0.489362 (-10175 6500);
PAINT SKYBLUE (-10175 6500);
DISPLAY INVISIBLE (-10175 6500);
FORCEPROP 1 LAST PACK_TYPE 0402LF
J 0
(-10475 6450);
DISPLAY 0.489362 (-10475 6450);
PAINT SKYBLUE (-10475 6450);
DISPLAY INVISIBLE (-10475 6450);
FORCEPROP 2 LAST CDS_LIB pure_quanta
J 0
(-10300 6525);
DISPLAY INVISIBLE (-10300 6525);
FORCEPROP 1 LAST PATH I215
J 2
(-10250 6675);
DISPLAY 0.978723 (-10250 6675);
PAINT WHITE (-10250 6675);
DISPLAY INVISIBLE (-10250 6675);
FORCEPROP 1 LAST PART_NUMBER CS00002JB13
J 0
(-10400 6575);
DISPLAY 0.489362 (-10400 6575);
PAINT SKYBLUE (-10400 6575);
DISPLAY INVISIBLE (-10400 6575);
FORCEADD OFFPAGE..2
(-9325 6525);
FORCEPROP 2 LAST $XR1 243 
J 0
(-9016 6525);
DISPLAY 0.638298 (-9016 6525);
PAINT MONO (-9016 6525);
FORCEPROP 2 LAST $XR0 241 
J 0
(-9136 6525);
DISPLAY 0.638298 (-9136 6525);
PAINT MONO (-9136 6525);
FORCEPROP 2 LAST CDS_LIB standard
J 0
(-9325 6525);
DISPLAY INVISIBLE (-9325 6525);
FORCEPROP 1 LAST OFFPAGE TRUE
J 0
(-9000 6400);
DISPLAY 0.872340 (-9000 6400);
PAINT GREEN (-9000 6400);
DISPLAY INVISIBLE (-9000 6400);
FORCEPROP 1 LAST COMMENT_BODY TRUE
J 0
(-9370 6430);
DISPLAY 0.872340 (-9370 6430);
PAINT PEACH (-9370 6430);
DISPLAY INVISIBLE (-9370 6430);
FORCEPROP 2 LAST PATH I216
J 0
(-9150 6600);
DISPLAY 0.680851 (-9150 6600);
DISPLAY INVISIBLE (-9150 6600);
FORCEADD OFFPAGE..4
(-10000 8575);
FORCEPROP 2 LAST $XR0 153 
J 0
(-9814 8575);
DISPLAY 0.638298 (-9814 8575);
PAINT MONO (-9814 8575);
FORCEPROP 2 LAST CDS_LIB standard
J 0
(-10000 8575);
DISPLAY INVISIBLE (-10000 8575);
FORCEPROP 1 LAST OFFPAGE TRUE
J 0
(-9675 8450);
DISPLAY 0.872340 (-9675 8450);
DISPLAY INVISIBLE (-9675 8450);
FORCEPROP 1 LAST COMMENT_BODY TRUE
J 0
(-10025 8475);
DISPLAY 0.872340 (-10025 8475);
PAINT GREEN (-10025 8475);
DISPLAY INVISIBLE (-10025 8475);
FORCEPROP 2 LAST PATH I217
J 0
(-9825 8650);
DISPLAY 0.680851 (-9825 8650);
DISPLAY INVISIBLE (-9825 8650);
FORCEADD Q_CAP..1
(-8500 6675);
FORCEPROP 1 LAST LOCATION C6000
J 0
(-8450 6775);
DISPLAY 0.638298 (-8450 6775);
FORCEPROP 0 LAST $SEC 1
J 0
(-8450 6825);
DISPLAY 0.680851 (-8450 6825);
PAINT MONO (-8450 6825);
DISPLAY INVISIBLE (-8450 6825);
FORCEPROP 0 LAST CDS_SEC 1
J 0
(-8450 6825);
DISPLAY 0.680851 (-8450 6825);
DISPLAY INVISIBLE (-8450 6825);
FORCEPROP 1 LASTPIN (-8500 6775) $PN 1
J 0
(-8490 6755);
DISPLAY 0.787234 (-8490 6755);
PAINT MONO (-8490 6755);
FORCEPROP 1 LASTPIN (-8500 6575) $PN 2
J 0
(-8490 6555);
DISPLAY 0.787234 (-8490 6555);
PAINT MONO (-8490 6555);
FORCEPROP 1 LAST PACK_TYPE 0402
J 0
(-8450 6475);
DISPLAY 0.638298 (-8450 6475);
FORCEPROP 1 LAST TOLERANCE 10%
J 0
(-8450 6625);
DISPLAY 0.638298 (-8450 6625);
FORCEPROP 1 LAST VALUE 0.1UF
J 0
(-8450 6725);
DISPLAY 0.638298 (-8450 6725);
FORCEPROP 1 LAST MATERIAL X7R
J 0
(-8450 6575);
DISPLAY 0.638298 (-8450 6575);
FORCEPROP 1 LAST VOLTAGE 25V
J 0
(-8450 6675);
DISPLAY 0.638298 (-8450 6675);
FORCEPROP 2 LAST CDS_LIB pure_quanta
J 0
(-8500 6675);
DISPLAY INVISIBLE (-8500 6675);
FORCEPROP 1 LAST PATH I219
J 0
(-8450 6825);
DISPLAY 0.978723 (-8450 6825);
PAINT WHITE (-8450 6825);
DISPLAY INVISIBLE (-8450 6825);
FORCEPROP 1 LAST PART_NUMBER CH4104K1B00
J 0
(-8450 6525);
DISPLAY 0.638298 (-8450 6525);
DISPLAY INVISIBLE (-8450 6525);
FORCEADD OFFPAGE..1
(-14100 5075);
FORCEPROP 2 LAST $XR0 234 
J 0
(-14352 5075);
DISPLAY 0.638298 (-14352 5075);
PAINT MONO (-14352 5075);
FORCEPROP 2 LAST CDS_LIB standard
J 0
(-14100 5075);
DISPLAY INVISIBLE (-14100 5075);
FORCEPROP 1 LAST OFFPAGE TRUE
J 0
(-13775 4950);
DISPLAY 0.872340 (-13775 4950);
PAINT GREEN (-13775 4950);
DISPLAY INVISIBLE (-13775 4950);
FORCEPROP 1 LAST COMMENT_BODY TRUE
J 0
(-13975 4975);
DISPLAY 0.872340 (-13975 4975);
PAINT PEACH (-13975 4975);
DISPLAY INVISIBLE (-13975 4975);
FORCEPROP 2 LAST PATH I22
J 0
(-14050 5150);
DISPLAY 0.680851 (-14050 5150);
DISPLAY INVISIBLE (-14050 5150);
FORCEADD Q_RES..2
(-16725 5525);
FORCEPROP 1 LAST LOCATION R4809
J 0
(-16680 5650);
DISPLAY 0.978723 (-16680 5650);
FORCEPROP 0 LAST $SEC 1
J 0
(-16675 5700);
DISPLAY 0.680851 (-16675 5700);
PAINT MONO (-16675 5700);
DISPLAY INVISIBLE (-16675 5700);
FORCEPROP 0 LAST CDS_SEC 1
J 0
(-16675 5700);
DISPLAY 0.680851 (-16675 5700);
DISPLAY INVISIBLE (-16675 5700);
FORCEPROP 1 LASTPIN (-16725 5625) $PN 1
J 0
(-16720 5587);
DISPLAY 0.787234 (-16720 5587);
PAINT MONO (-16720 5587);
FORCEPROP 1 LASTPIN (-16725 5425) $PN 2
J 0
(-16720 5435);
DISPLAY 0.787234 (-16720 5435);
PAINT MONO (-16720 5435);
FORCEPROP 1 LAST VALUE 0
J 0
(-16680 5600);
DISPLAY 0.978723 (-16680 5600);
FORCEPROP 1 LAST TOLERANCE 5%
J 0
(-16680 5550);
DISPLAY 0.978723 (-16680 5550);
FORCEPROP 1 LAST MATERIAL CHIP
J 0
(-16685 5450);
DISPLAY 0.978723 (-16685 5450);
FORCEPROP 1 LAST WATTAGE 1/16W
J 0
(-16685 5500);
DISPLAY 0.978723 (-16685 5500);
FORCEPROP 1 LAST PACK_TYPE 0402LF
J 0
(-16685 5350);
DISPLAY 0.978723 (-16685 5350);
FORCEPROP 2 LAST CDS_LIB pure_quanta
J 0
(-16725 5525);
DISPLAY INVISIBLE (-16725 5525);
FORCEPROP 1 LAST PATH I220
J 0
(-16675 5700);
DISPLAY 0.978723 (-16675 5700);
PAINT WHITE (-16675 5700);
DISPLAY INVISIBLE (-16675 5700);
FORCEPROP 1 LAST PART_NUMBER CS00002JB13
J 0
(-16685 5400);
DISPLAY 0.978723 (-16685 5400);
DISPLAY INVISIBLE (-16685 5400);
FORCEADD UNIVERSAL_GND..1
(-16725 5225);
FORCEPROP 3 LASTPIN (-16725 5275) SIG_NAME GND\g
J 0
(-16715 5285);
DISPLAY 0.659574 (-16715 5285);
PAINT MONO (-16715 5285);
DISPLAY INVISIBLE (-16715 5285);
FORCEPROP 2 LAST CDS_LIB pure_quanta_power
J 0
(-16725 5225);
DISPLAY INVISIBLE (-16725 5225);
FORCEPROP 1 LAST HDL_POWER GND
J 1
(-16700 5150);
DISPLAY 0.702128 (-16700 5150);
PAINT GREEN (-16700 5150);
DISPLAY INVISIBLE (-16700 5150);
FORCEPROP 1 LAST PATH I221
J 0
(-16650 5225);
DISPLAY 0.872340 (-16650 5225);
PAINT AQUA (-16650 5225);
DISPLAY INVISIBLE (-16650 5225);
FORCEADD OFFPAGE..1
(-14100 5125);
FORCEPROP 2 LAST $XR0 234 
J 0
(-14352 5125);
DISPLAY 0.638298 (-14352 5125);
PAINT MONO (-14352 5125);
FORCEPROP 2 LAST CDS_LIB standard
J 0
(-14100 5125);
DISPLAY INVISIBLE (-14100 5125);
FORCEPROP 1 LAST OFFPAGE TRUE
J 0
(-13775 5000);
DISPLAY 0.872340 (-13775 5000);
PAINT GREEN (-13775 5000);
DISPLAY INVISIBLE (-13775 5000);
FORCEPROP 1 LAST COMMENT_BODY TRUE
J 0
(-13975 5025);
DISPLAY 0.872340 (-13975 5025);
PAINT PEACH (-13975 5025);
DISPLAY INVISIBLE (-13975 5025);
FORCEPROP 2 LAST PATH I23
J 0
(-14050 5200);
DISPLAY 0.680851 (-14050 5200);
DISPLAY INVISIBLE (-14050 5200);
FORCEADD Q_RES..1
(-14975 5725);
FORCEPROP 1 LAST LOCATION R321
J 0
(-15200 5725);
DISPLAY 0.702128 (-15200 5725);
FORCEPROP 2 LAST $SEC 1
J 2
(-15025 5925);
DISPLAY 0.680851 (-15025 5925);
PAINT MONO (-15025 5925);
DISPLAY INVISIBLE (-15025 5925);
FORCEPROP 2 LAST CDS_SEC 1
J 2
(-15025 5925);
DISPLAY 1.021277 (-15025 5925);
DISPLAY INVISIBLE (-15025 5925);
FORCEPROP 1 LASTPIN (-15075 5725) $PN 1
R 2
J 2
(-15063 5811);
DISPLAY 0.808511 (-15063 5811);
PAINT WHITE (-15063 5811);
DISPLAY INVISIBLE (-15063 5811);
FORCEPROP 1 LASTPIN (-14875 5725) $PN 2
R 2
J 2
(-14913 5811);
DISPLAY 0.808511 (-14913 5811);
PAINT WHITE (-14913 5811);
DISPLAY INVISIBLE (-14913 5811);
FORCEPROP 1 LAST MATERIAL CHIP
J 0
(-14725 5725);
DISPLAY 0.510638 (-14725 5725);
FORCEPROP 1 LAST TOLERANCE 5%
J 0
(-14800 5725);
DISPLAY 0.510638 (-14800 5725);
FORCEPROP 1 LAST VALUE 0
J 2
(-14825 5725);
DISPLAY 0.510638 (-14825 5725);
FORCEPROP 1 LAST PACK_TYPE 0402LF
J 0
(-15125 5825);
DISPLAY 0.510638 (-15125 5825);
DISPLAY INVISIBLE (-15125 5825);
FORCEPROP 1 LAST WATTAGE 1/16W
J 2
(-14825 5825);
DISPLAY 0.510638 (-14825 5825);
DISPLAY INVISIBLE (-14825 5825);
FORCEPROP 2 LAST CDS_LIB pure_quanta
J 0
(-14975 5819);
DISPLAY INVISIBLE (-14975 5819);
FORCEPROP 1 LAST PATH I24
J 0
(-15025 5875);
DISPLAY 0.978723 (-15025 5875);
PAINT WHITE (-15025 5875);
DISPLAY INVISIBLE (-15025 5875);
FORCEPROP 1 LAST PART_NUMBER CS00002JB13
J 0
(-15125 5775);
DISPLAY 0.510638 (-15125 5775);
DISPLAY INVISIBLE (-15125 5775);
FORCEADD Q_RES..1
(-14975 5775);
FORCEPROP 1 LAST LOCATION R3777
J 0
(-15200 5775);
DISPLAY 0.638298 (-15200 5775);
FORCEPROP 0 LAST $SEC 1
J 0
(-15025 5875);
DISPLAY 0.680851 (-15025 5875);
PAINT MONO (-15025 5875);
DISPLAY INVISIBLE (-15025 5875);
FORCEPROP 0 LAST CDS_SEC 1
J 0
(-15025 5875);
DISPLAY 1.021277 (-15025 5875);
DISPLAY INVISIBLE (-15025 5875);
FORCEPROP 1 LASTPIN (-15075 5775) $PN 1
J 0
(-15063 5787);
DISPLAY 0.787234 (-15063 5787);
PAINT MONO (-15063 5787);
FORCEPROP 1 LASTPIN (-14875 5775) $PN 2
J 0
(-14913 5787);
DISPLAY 0.787234 (-14913 5787);
PAINT MONO (-14913 5787);
FORCEPROP 1 LAST MATERIAL CHIP
J 0
(-14725 5775);
DISPLAY 0.510638 (-14725 5775);
FORCEPROP 1 LAST TOLERANCE 5%
J 0
(-14800 5775);
DISPLAY 0.510638 (-14800 5775);
FORCEPROP 1 LAST VALUE 0
J 2
(-14825 5775);
DISPLAY 0.510638 (-14825 5775);
FORCEPROP 1 LAST WATTAGE 1/16W
J 2
(-14825 5875);
DISPLAY 0.510638 (-14825 5875);
DISPLAY INVISIBLE (-14825 5875);
FORCEPROP 1 LAST PACK_TYPE 0402LF
J 0
(-15125 5875);
DISPLAY 0.510638 (-15125 5875);
DISPLAY INVISIBLE (-15125 5875);
FORCEPROP 2 LAST CDS_LIB pure_quanta
J 0
(-14975 5775);
DISPLAY INVISIBLE (-14975 5775);
FORCEPROP 1 LAST PATH I25
J 0
(-15025 5925);
DISPLAY 0.978723 (-15025 5925);
PAINT WHITE (-15025 5925);
DISPLAY INVISIBLE (-15025 5925);
FORCEPROP 1 LAST PART_NUMBER CS00002JB13
J 0
(-15125 5825);
DISPLAY 0.510638 (-15125 5825);
DISPLAY INVISIBLE (-15125 5825);
FORCEADD Q_RES..1
(-14975 5875);
FORCEPROP 1 LAST LOCATION R1798
J 0
(-15200 5875);
DISPLAY 0.638298 (-15200 5875);
FORCEPROP 0 LAST $SEC 1
J 0
(-14725 5900);
DISPLAY 0.680851 (-14725 5900);
PAINT MONO (-14725 5900);
DISPLAY INVISIBLE (-14725 5900);
FORCEPROP 0 LAST CDS_SEC 1
J 0
(-14725 5900);
DISPLAY 1.021277 (-14725 5900);
DISPLAY INVISIBLE (-14725 5900);
FORCEPROP 1 LASTPIN (-15075 5875) $PN 1
J 0
(-15063 5887);
DISPLAY 0.638298 (-15063 5887);
PAINT MONO (-15063 5887);
FORCEPROP 1 LASTPIN (-14875 5875) $PN 2
J 0
(-14913 5887);
DISPLAY 0.638298 (-14913 5887);
PAINT MONO (-14913 5887);
FORCEPROP 1 LAST MATERIAL CHIP
J 0
(-14725 5875);
DISPLAY 0.510638 (-14725 5875);
FORCEPROP 1 LAST TOLERANCE 5%
J 0
(-14800 5875);
DISPLAY 0.510638 (-14800 5875);
FORCEPROP 1 LAST VALUE 0
J 2
(-14825 5875);
DISPLAY 0.510638 (-14825 5875);
FORCEPROP 1 LAST PACK_TYPE 0402LF
J 0
(-15125 5975);
DISPLAY 0.510638 (-15125 5975);
DISPLAY INVISIBLE (-15125 5975);
FORCEPROP 1 LAST WATTAGE 1/16W
J 2
(-14825 5975);
DISPLAY 0.510638 (-14825 5975);
DISPLAY INVISIBLE (-14825 5975);
FORCEPROP 2 LAST CDS_LIB pure_quanta
J 0
(-14975 5875);
DISPLAY INVISIBLE (-14975 5875);
FORCEPROP 1 LAST PATH I26
J 0
(-15025 6025);
DISPLAY 0.978723 (-15025 6025);
PAINT WHITE (-15025 6025);
DISPLAY INVISIBLE (-15025 6025);
FORCEPROP 1 LAST PART_NUMBER CS00002JB13
J 0
(-15125 5925);
DISPLAY 0.510638 (-15125 5925);
DISPLAY INVISIBLE (-15125 5925);
FORCEADD Q_RES..1
(-14975 5925);
FORCEPROP 1 LAST LOCATION R3776
J 0
(-15200 5925);
DISPLAY 0.638298 (-15200 5925);
FORCEPROP 0 LAST $SEC 1
J 0
(-15025 6025);
DISPLAY 0.680851 (-15025 6025);
PAINT MONO (-15025 6025);
DISPLAY INVISIBLE (-15025 6025);
FORCEPROP 0 LAST CDS_SEC 1
J 0
(-15025 6025);
DISPLAY 1.021277 (-15025 6025);
DISPLAY INVISIBLE (-15025 6025);
FORCEPROP 1 LASTPIN (-15075 5925) $PN 1
J 0
(-15063 5937);
DISPLAY 0.787234 (-15063 5937);
PAINT MONO (-15063 5937);
FORCEPROP 1 LASTPIN (-14875 5925) $PN 2
J 0
(-14913 5937);
DISPLAY 0.787234 (-14913 5937);
PAINT MONO (-14913 5937);
FORCEPROP 1 LAST MATERIAL CHIP
J 0
(-14725 5925);
DISPLAY 0.510638 (-14725 5925);
FORCEPROP 1 LAST TOLERANCE 5%
J 0
(-14800 5925);
DISPLAY 0.510638 (-14800 5925);
FORCEPROP 1 LAST VALUE 0
J 2
(-14825 5925);
DISPLAY 0.510638 (-14825 5925);
FORCEPROP 1 LAST PACK_TYPE 0402LF
J 0
(-15125 6025);
DISPLAY 0.510638 (-15125 6025);
DISPLAY INVISIBLE (-15125 6025);
FORCEPROP 1 LAST WATTAGE 1/16W
J 2
(-14825 6025);
DISPLAY 0.510638 (-14825 6025);
DISPLAY INVISIBLE (-14825 6025);
FORCEPROP 2 LAST CDS_LIB pure_quanta
J 0
(-14975 5925);
DISPLAY INVISIBLE (-14975 5925);
FORCEPROP 1 LAST PATH I27
J 0
(-15025 6075);
DISPLAY 0.978723 (-15025 6075);
PAINT WHITE (-15025 6075);
DISPLAY INVISIBLE (-15025 6075);
FORCEPROP 1 LAST PART_NUMBER CS00002JB13
J 0
(-15125 5975);
DISPLAY 0.510638 (-15125 5975);
DISPLAY INVISIBLE (-15125 5975);
FORCEADD Q_RES..1
(-14950 6075);
FORCEPROP 1 LAST LOCATION R6032
J 0
(-15200 6075);
DISPLAY 0.638298 (-15200 6075);
FORCEPROP 2 LAST $SEC 1
J 0
(-15000 6275);
DISPLAY 0.680851 (-15000 6275);
PAINT MONO (-15000 6275);
DISPLAY INVISIBLE (-15000 6275);
FORCEPROP 2 LAST CDS_SEC 1
J 0
(-15000 6275);
DISPLAY 1.021277 (-15000 6275);
DISPLAY INVISIBLE (-15000 6275);
FORCEPROP 1 LASTPIN (-15050 6075) $PN 1
J 0
(-15038 6087);
DISPLAY 0.787234 (-15038 6087);
FORCEPROP 1 LASTPIN (-14850 6075) $PN 2
J 0
(-14888 6087);
DISPLAY 0.787234 (-14888 6087);
FORCEPROP 1 LAST TOLERANCE 5%
J 0
(-14775 6075);
DISPLAY 0.510638 (-14775 6075);
FORCEPROP 1 LAST VALUE 0
J 2
(-14800 6075);
DISPLAY 0.510638 (-14800 6075);
FORCEPROP 1 LAST MATERIAL CHIP
J 0
(-14700 6075);
DISPLAY 0.510638 (-14700 6075);
FORCEPROP 1 LAST PACK_TYPE 0402LF
J 0
(-15100 5975);
DISPLAY 0.510638 (-15100 5975);
DISPLAY INVISIBLE (-15100 5975);
FORCEPROP 1 LAST WATTAGE 1/16W
J 2
(-14800 5975);
DISPLAY 0.510638 (-14800 5975);
DISPLAY INVISIBLE (-14800 5975);
FORCEPROP 2 LAST CDS_LIB pure_quanta
J 0
(-14950 6075);
PAINT MONO (-14950 6075);
DISPLAY INVISIBLE (-14950 6075);
FORCEPROP 1 LAST PATH I28
J 0
(-15000 6225);
DISPLAY 0.978723 (-15000 6225);
PAINT WHITE (-15000 6225);
DISPLAY INVISIBLE (-15000 6225);
FORCEPROP 1 LAST PART_NUMBER CS00002JB13
J 0
(-15100 6025);
DISPLAY 0.510638 (-15100 6025);
DISPLAY INVISIBLE (-15100 6025);
FORCEADD Q_RES..1
(-14950 6175);
FORCEPROP 1 LAST LOCATION R1815
J 0
(-15200 6175);
DISPLAY 0.638298 (-15200 6175);
FORCEPROP 2 LAST $SEC 1
J 0
(-15000 6375);
DISPLAY 0.680851 (-15000 6375);
PAINT MONO (-15000 6375);
DISPLAY INVISIBLE (-15000 6375);
FORCEPROP 2 LAST CDS_SEC 1
J 0
(-15000 6375);
DISPLAY 1.021277 (-15000 6375);
DISPLAY INVISIBLE (-15000 6375);
FORCEPROP 1 LASTPIN (-15050 6175) $PN 1
J 0
(-15038 6187);
DISPLAY 0.787234 (-15038 6187);
FORCEPROP 1 LASTPIN (-14850 6175) $PN 2
J 0
(-14888 6187);
DISPLAY 0.787234 (-14888 6187);
FORCEPROP 1 LAST VALUE 0
J 2
(-14800 6175);
DISPLAY 0.510638 (-14800 6175);
FORCEPROP 1 LAST TOLERANCE 5%
J 0
(-14775 6175);
DISPLAY 0.510638 (-14775 6175);
FORCEPROP 1 LAST MATERIAL CHIP
J 0
(-14700 6175);
DISPLAY 0.510638 (-14700 6175);
FORCEPROP 1 LAST PACK_TYPE 0402LF
J 0
(-15100 6075);
DISPLAY 0.510638 (-15100 6075);
DISPLAY INVISIBLE (-15100 6075);
FORCEPROP 1 LAST WATTAGE 1/16W
J 2
(-14800 6075);
DISPLAY 0.510638 (-14800 6075);
DISPLAY INVISIBLE (-14800 6075);
FORCEPROP 2 LAST CDS_LIB pure_quanta
J 0
(-14950 6175);
PAINT MONO (-14950 6175);
DISPLAY INVISIBLE (-14950 6175);
FORCEPROP 1 LAST PATH I29
J 0
(-15000 6325);
DISPLAY 0.978723 (-15000 6325);
PAINT WHITE (-15000 6325);
DISPLAY INVISIBLE (-15000 6325);
FORCEPROP 1 LAST PART_NUMBER CS00002JB13
J 0
(-15100 6125);
DISPLAY 0.510638 (-15100 6125);
DISPLAY INVISIBLE (-15100 6125);
FORCEADD OFFPAGE..1
(-16225 5925);
FORCEPROP 2 LAST $XR0 80 
J 0
(-16446 5925);
DISPLAY 0.638298 (-16446 5925);
PAINT MONO (-16446 5925);
FORCEPROP 2 LAST CDS_LIB standard
J 0
(-16225 5925);
DISPLAY INVISIBLE (-16225 5925);
FORCEPROP 1 LAST OFFPAGE TRUE
J 0
(-15900 5800);
DISPLAY 0.872340 (-15900 5800);
PAINT GREEN (-15900 5800);
DISPLAY INVISIBLE (-15900 5800);
FORCEPROP 1 LAST COMMENT_BODY TRUE
J 0
(-16100 5825);
DISPLAY 0.872340 (-16100 5825);
PAINT PEACH (-16100 5825);
DISPLAY INVISIBLE (-16100 5825);
FORCEPROP 2 LAST PATH I3
J 0
(-16175 6000);
DISPLAY 0.680851 (-16175 6000);
DISPLAY INVISIBLE (-16175 6000);
FORCEADD Q_RES..1
(-14950 6225);
FORCEPROP 1 LAST LOCATION R6033
J 0
(-15200 6225);
DISPLAY 0.638298 (-15200 6225);
FORCEPROP 2 LAST $SEC 1
J 0
(-15000 6425);
DISPLAY 0.680851 (-15000 6425);
PAINT MONO (-15000 6425);
DISPLAY INVISIBLE (-15000 6425);
FORCEPROP 2 LAST CDS_SEC 1
J 0
(-15000 6425);
DISPLAY 1.021277 (-15000 6425);
DISPLAY INVISIBLE (-15000 6425);
FORCEPROP 1 LASTPIN (-15050 6225) $PN 1
J 0
(-15038 6237);
DISPLAY 0.787234 (-15038 6237);
FORCEPROP 1 LASTPIN (-14850 6225) $PN 2
J 0
(-14888 6237);
DISPLAY 0.787234 (-14888 6237);
FORCEPROP 1 LAST VALUE 0
J 2
(-14800 6225);
DISPLAY 0.510638 (-14800 6225);
FORCEPROP 1 LAST TOLERANCE 5%
J 0
(-14775 6225);
DISPLAY 0.510638 (-14775 6225);
FORCEPROP 1 LAST MATERIAL CHIP
J 0
(-14700 6225);
DISPLAY 0.510638 (-14700 6225);
FORCEPROP 2 LAST CDS_LIB pure_quanta
J 0
(-14950 6225);
PAINT MONO (-14950 6225);
DISPLAY INVISIBLE (-14950 6225);
FORCEPROP 1 LAST WATTAGE 1/16W
J 2
(-14800 6125);
DISPLAY 0.510638 (-14800 6125);
DISPLAY INVISIBLE (-14800 6125);
FORCEPROP 1 LAST PACK_TYPE 0402LF
J 0
(-15100 6125);
DISPLAY 0.510638 (-15100 6125);
DISPLAY INVISIBLE (-15100 6125);
FORCEPROP 1 LAST PATH I30
J 0
(-15000 6375);
DISPLAY 0.978723 (-15000 6375);
PAINT WHITE (-15000 6375);
DISPLAY INVISIBLE (-15000 6375);
FORCEPROP 1 LAST PART_NUMBER CS00002JB13
J 0
(-15100 6175);
DISPLAY 0.510638 (-15100 6175);
DISPLAY INVISIBLE (-15100 6175);
FORCEADD Q_RES..1
(-14950 6375);
FORCEPROP 1 LAST LOCATION R4087
J 0
(-15200 6375);
DISPLAY 0.638298 (-15200 6375);
FORCEPROP 0 LAST $SEC 1
J 0
(-15125 6425);
DISPLAY 0.680851 (-15125 6425);
PAINT MONO (-15125 6425);
DISPLAY INVISIBLE (-15125 6425);
FORCEPROP 0 LAST CDS_SEC 1
J 0
(-15125 6425);
DISPLAY 1.021277 (-15125 6425);
DISPLAY INVISIBLE (-15125 6425);
FORCEPROP 1 LASTPIN (-15050 6375) $PN 1
J 0
(-15038 6387);
DISPLAY 0.787234 (-15038 6387);
PAINT MONO (-15038 6387);
FORCEPROP 1 LASTPIN (-14850 6375) $PN 2
J 0
(-14888 6387);
DISPLAY 0.787234 (-14888 6387);
PAINT MONO (-14888 6387);
FORCEPROP 1 LAST VALUE 0
J 2
(-14800 6375);
DISPLAY 0.510638 (-14800 6375);
FORCEPROP 1 LAST TOLERANCE 5%
J 0
(-14775 6375);
DISPLAY 0.510638 (-14775 6375);
FORCEPROP 1 LAST MATERIAL CHIP
J 0
(-14700 6375);
DISPLAY 0.510638 (-14700 6375);
FORCEPROP 2 LAST CDS_LIB pure_quanta
J 0
(-14950 6375);
DISPLAY INVISIBLE (-14950 6375);
FORCEPROP 1 LAST PACK_TYPE 0402LF
J 0
(-15100 6475);
DISPLAY 0.510638 (-15100 6475);
DISPLAY INVISIBLE (-15100 6475);
FORCEPROP 1 LAST WATTAGE 1/16W
J 2
(-14800 6475);
DISPLAY 0.510638 (-14800 6475);
DISPLAY INVISIBLE (-14800 6475);
FORCEPROP 1 LAST PATH I31
J 0
(-15000 6525);
DISPLAY 0.978723 (-15000 6525);
PAINT WHITE (-15000 6525);
DISPLAY INVISIBLE (-15000 6525);
FORCEPROP 1 LAST PART_NUMBER CS00002JB13
J 0
(-15100 6425);
DISPLAY 0.510638 (-15100 6425);
DISPLAY INVISIBLE (-15100 6425);
FORCEADD Q_RES..1
(-14950 6325);
FORCEPROP 1 LAST LOCATION R1816
J 0
(-15200 6325);
DISPLAY 0.638298 (-15200 6325);
FORCEPROP 2 LAST $SEC 1
J 0
(-15000 6525);
DISPLAY 0.680851 (-15000 6525);
PAINT MONO (-15000 6525);
DISPLAY INVISIBLE (-15000 6525);
FORCEPROP 2 LAST CDS_SEC 1
J 0
(-15000 6525);
DISPLAY 1.021277 (-15000 6525);
DISPLAY INVISIBLE (-15000 6525);
FORCEPROP 1 LASTPIN (-15050 6325) $PN 1
J 0
(-15038 6337);
DISPLAY 0.787234 (-15038 6337);
FORCEPROP 1 LASTPIN (-14850 6325) $PN 2
J 0
(-14888 6337);
DISPLAY 0.787234 (-14888 6337);
FORCEPROP 1 LAST VALUE 0
J 2
(-14800 6325);
DISPLAY 0.510638 (-14800 6325);
FORCEPROP 1 LAST MATERIAL CHIP
J 0
(-14700 6325);
DISPLAY 0.510638 (-14700 6325);
FORCEPROP 1 LAST TOLERANCE 5%
J 0
(-14775 6325);
DISPLAY 0.510638 (-14775 6325);
FORCEPROP 1 LAST WATTAGE 1/16W
J 2
(-14800 6225);
DISPLAY 0.510638 (-14800 6225);
DISPLAY INVISIBLE (-14800 6225);
FORCEPROP 1 LAST PACK_TYPE 0402LF
J 0
(-15100 6225);
DISPLAY 0.510638 (-15100 6225);
DISPLAY INVISIBLE (-15100 6225);
FORCEPROP 2 LAST CDS_LIB pure_quanta
J 0
(-14950 6325);
PAINT MONO (-14950 6325);
DISPLAY INVISIBLE (-14950 6325);
FORCEPROP 1 LAST PATH I32
J 0
(-15000 6475);
DISPLAY 0.978723 (-15000 6475);
PAINT WHITE (-15000 6475);
DISPLAY INVISIBLE (-15000 6475);
FORCEPROP 1 LAST PART_NUMBER CS00002JB13
J 0
(-15100 6275);
DISPLAY 0.510638 (-15100 6275);
DISPLAY INVISIBLE (-15100 6275);
FORCEADD Q_RES..1
(-14950 6675);
FORCEPROP 1 LAST LOCATION R2416
J 0
(-15175 6675);
DISPLAY 0.638298 (-15175 6675);
FORCEPROP 0 LAST $SEC 1
J 0
(-15175 6725);
DISPLAY 0.680851 (-15175 6725);
PAINT MONO (-15175 6725);
DISPLAY INVISIBLE (-15175 6725);
FORCEPROP 0 LAST CDS_SEC 1
J 0
(-15175 6725);
DISPLAY 1.021277 (-15175 6725);
DISPLAY INVISIBLE (-15175 6725);
FORCEPROP 1 LASTPIN (-15050 6675) $PN 1
J 0
(-15038 6687);
DISPLAY 0.787234 (-15038 6687);
PAINT MONO (-15038 6687);
FORCEPROP 1 LASTPIN (-14850 6675) $PN 2
J 0
(-14888 6687);
DISPLAY 0.787234 (-14888 6687);
PAINT MONO (-14888 6687);
FORCEPROP 1 LAST VALUE 33.2
J 2
(-14750 6675);
DISPLAY 0.510638 (-14750 6675);
FORCEPROP 1 LAST MATERIAL CHIP
J 0
(-14650 6675);
DISPLAY 0.510638 (-14650 6675);
FORCEPROP 1 LAST TOLERANCE 1%
J 0
(-14725 6675);
DISPLAY 0.510638 (-14725 6675);
FORCEPROP 1 LAST WATTAGE 1/16W
J 2
(-14850 6775);
DISPLAY 0.404255 (-14850 6775);
DISPLAY INVISIBLE (-14850 6775);
FORCEPROP 1 LAST PACK_TYPE 0402LF
J 0
(-15075 6775);
DISPLAY 0.404255 (-15075 6775);
DISPLAY INVISIBLE (-15075 6775);
FORCEPROP 2 LAST CDS_LIB pure_quanta
J 0
(-14950 6675);
DISPLAY INVISIBLE (-14950 6675);
FORCEPROP 1 LAST PATH I33
J 0
(-15000 6825);
DISPLAY 0.978723 (-15000 6825);
PAINT WHITE (-15000 6825);
DISPLAY INVISIBLE (-15000 6825);
FORCEPROP 1 LAST PART_NUMBER CS03322FB03
J 0
(-15075 6725);
DISPLAY 0.404255 (-15075 6725);
DISPLAY INVISIBLE (-15075 6725);
FORCEADD Q_RES..1
(-14950 6575);
FORCEPROP 1 LAST LOCATION R2418
J 0
(-15175 6575);
DISPLAY 0.638298 (-15175 6575);
FORCEPROP 0 LAST $SEC 1
J 0
(-15175 6625);
DISPLAY 0.680851 (-15175 6625);
PAINT MONO (-15175 6625);
DISPLAY INVISIBLE (-15175 6625);
FORCEPROP 0 LAST CDS_SEC 1
J 0
(-15175 6625);
DISPLAY 1.021277 (-15175 6625);
DISPLAY INVISIBLE (-15175 6625);
FORCEPROP 1 LASTPIN (-15050 6575) $PN 1
J 0
(-15038 6587);
DISPLAY 0.787234 (-15038 6587);
PAINT MONO (-15038 6587);
FORCEPROP 1 LASTPIN (-14850 6575) $PN 2
J 0
(-14888 6587);
DISPLAY 0.787234 (-14888 6587);
PAINT MONO (-14888 6587);
FORCEPROP 1 LAST MATERIAL CHIP
J 0
(-14650 6575);
DISPLAY 0.510638 (-14650 6575);
FORCEPROP 1 LAST VALUE 33.2
J 2
(-14750 6575);
DISPLAY 0.510638 (-14750 6575);
FORCEPROP 1 LAST TOLERANCE 1%
J 0
(-14725 6575);
DISPLAY 0.510638 (-14725 6575);
FORCEPROP 2 LAST CDS_LIB pure_quanta
J 0
(-14950 6575);
DISPLAY INVISIBLE (-14950 6575);
FORCEPROP 1 LAST PACK_TYPE 0402LF
J 0
(-15075 6675);
DISPLAY 0.404255 (-15075 6675);
DISPLAY INVISIBLE (-15075 6675);
FORCEPROP 1 LAST WATTAGE 1/16W
J 2
(-14850 6675);
DISPLAY 0.404255 (-14850 6675);
DISPLAY INVISIBLE (-14850 6675);
FORCEPROP 1 LAST PATH I34
J 0
(-15000 6725);
DISPLAY 0.978723 (-15000 6725);
PAINT WHITE (-15000 6725);
DISPLAY INVISIBLE (-15000 6725);
FORCEPROP 1 LAST PART_NUMBER CS03322FB03
J 0
(-15075 6625);
DISPLAY 0.404255 (-15075 6625);
DISPLAY INVISIBLE (-15075 6625);
FORCEADD Q_RES..1
(-14950 6625);
FORCEPROP 1 LAST LOCATION R2417
J 0
(-15175 6625);
DISPLAY 0.638298 (-15175 6625);
FORCEPROP 0 LAST $SEC 1
J 0
(-15175 6675);
DISPLAY 0.680851 (-15175 6675);
PAINT MONO (-15175 6675);
DISPLAY INVISIBLE (-15175 6675);
FORCEPROP 0 LAST CDS_SEC 1
J 0
(-15175 6675);
DISPLAY 1.021277 (-15175 6675);
DISPLAY INVISIBLE (-15175 6675);
FORCEPROP 1 LASTPIN (-15050 6625) $PN 1
J 0
(-15038 6637);
DISPLAY 0.787234 (-15038 6637);
PAINT MONO (-15038 6637);
FORCEPROP 1 LASTPIN (-14850 6625) $PN 2
J 0
(-14888 6637);
DISPLAY 0.787234 (-14888 6637);
PAINT MONO (-14888 6637);
FORCEPROP 1 LAST TOLERANCE 1%
J 0
(-14725 6625);
DISPLAY 0.510638 (-14725 6625);
FORCEPROP 1 LAST VALUE 33.2
J 2
(-14750 6625);
DISPLAY 0.510638 (-14750 6625);
FORCEPROP 1 LAST MATERIAL CHIP
J 0
(-14650 6625);
DISPLAY 0.510638 (-14650 6625);
FORCEPROP 2 LAST CDS_LIB pure_quanta
J 0
(-14950 6625);
DISPLAY INVISIBLE (-14950 6625);
FORCEPROP 1 LAST PACK_TYPE 0402LF
J 0
(-15075 6725);
DISPLAY 0.404255 (-15075 6725);
DISPLAY INVISIBLE (-15075 6725);
FORCEPROP 1 LAST WATTAGE 1/16W
J 2
(-14850 6725);
DISPLAY 0.404255 (-14850 6725);
DISPLAY INVISIBLE (-14850 6725);
FORCEPROP 1 LAST PATH I35
J 0
(-15000 6775);
DISPLAY 0.978723 (-15000 6775);
PAINT WHITE (-15000 6775);
DISPLAY INVISIBLE (-15000 6775);
FORCEPROP 1 LAST PART_NUMBER CS03322FB03
J 0
(-15075 6675);
DISPLAY 0.404255 (-15075 6675);
DISPLAY INVISIBLE (-15075 6675);
FORCEADD OFFPAGE..1
(-14100 5975);
FORCEPROP 2 LAST $XR0 81 
J 0
(-14351 5975);
DISPLAY 0.638298 (-14351 5975);
PAINT MONO (-14351 5975);
FORCEPROP 2 LAST CDS_LIB standard
J 0
(-14100 5975);
DISPLAY INVISIBLE (-14100 5975);
FORCEPROP 1 LAST OFFPAGE TRUE
J 0
(-13775 5850);
DISPLAY 0.872340 (-13775 5850);
PAINT GREEN (-13775 5850);
DISPLAY INVISIBLE (-13775 5850);
FORCEPROP 1 LAST COMMENT_BODY TRUE
J 0
(-13975 5875);
DISPLAY 0.872340 (-13975 5875);
PAINT PEACH (-13975 5875);
DISPLAY INVISIBLE (-13975 5875);
FORCEPROP 2 LAST PATH I36
J 0
(-14050 6050);
DISPLAY 0.680851 (-14050 6050);
DISPLAY INVISIBLE (-14050 6050);
FORCEADD OFFPAGE..5
(-14100 5675);
FORCEPROP 2 LAST $XR1 152 
J 0
(-14444 5675);
DISPLAY 0.638298 (-14444 5675);
PAINT MONO (-14444 5675);
FORCEPROP 2 LAST $XR0 82 
J 0
(-14324 5675);
DISPLAY 0.638298 (-14324 5675);
PAINT MONO (-14324 5675);
FORCEPROP 2 LAST CDS_LIB standard
J 0
(-14100 5675);
DISPLAY INVISIBLE (-14100 5675);
FORCEPROP 1 LAST OFFPAGE TRUE
J 0
(-13775 5550);
DISPLAY 0.872340 (-13775 5550);
PAINT GREEN (-13775 5550);
DISPLAY INVISIBLE (-13775 5550);
FORCEPROP 1 LAST COMMENT_BODY TRUE
J 0
(-14000 5600);
DISPLAY 0.872340 (-14000 5600);
PAINT PEACH (-14000 5600);
DISPLAY INVISIBLE (-14000 5600);
FORCEPROP 2 LAST PATH I37
J 0
(-14050 5750);
DISPLAY 0.680851 (-14050 5750);
DISPLAY INVISIBLE (-14050 5750);
FORCEADD OFFPAGE..5
(-14100 5575);
FORCEPROP 2 LAST $XR0 180 
J 0
(-14355 5575);
DISPLAY 0.638298 (-14355 5575);
PAINT MONO (-14355 5575);
FORCEPROP 2 LAST CDS_LIB standard
J 0
(-14100 5575);
DISPLAY INVISIBLE (-14100 5575);
FORCEPROP 1 LAST OFFPAGE TRUE
J 0
(-13775 5450);
DISPLAY 0.872340 (-13775 5450);
PAINT GREEN (-13775 5450);
DISPLAY INVISIBLE (-13775 5450);
FORCEPROP 1 LAST COMMENT_BODY TRUE
J 0
(-14000 5500);
DISPLAY 0.872340 (-14000 5500);
PAINT PEACH (-14000 5500);
DISPLAY INVISIBLE (-14000 5500);
FORCEPROP 2 LAST PATH I38
J 0
(-14050 5650);
DISPLAY 0.680851 (-14050 5650);
DISPLAY INVISIBLE (-14050 5650);
FORCEADD OFFPAGE..5
(-14100 5525);
FORCEPROP 2 LAST $XR0 180 
J 0
(-14355 5525);
DISPLAY 0.638298 (-14355 5525);
PAINT MONO (-14355 5525);
FORCEPROP 2 LAST CDS_LIB standard
J 0
(-14100 5525);
DISPLAY INVISIBLE (-14100 5525);
FORCEPROP 1 LAST OFFPAGE TRUE
J 0
(-13775 5400);
DISPLAY 0.872340 (-13775 5400);
PAINT GREEN (-13775 5400);
DISPLAY INVISIBLE (-13775 5400);
FORCEPROP 1 LAST COMMENT_BODY TRUE
J 0
(-14000 5450);
DISPLAY 0.872340 (-14000 5450);
PAINT PEACH (-14000 5450);
DISPLAY INVISIBLE (-14000 5450);
FORCEPROP 2 LAST PATH I39
J 0
(-14050 5600);
DISPLAY 0.680851 (-14050 5600);
DISPLAY INVISIBLE (-14050 5600);
FORCEADD OFFPAGE..5
(-16225 5875);
FORCEPROP 2 LAST $XR0 150 
J 0
(-16480 5875);
DISPLAY 0.638298 (-16480 5875);
PAINT MONO (-16480 5875);
FORCEPROP 2 LAST $XR1 80 
J 0
(-16570 5875);
DISPLAY 0.638298 (-16570 5875);
PAINT MONO (-16570 5875);
FORCEPROP 2 LAST CDS_LIB standard
J 0
(-16225 5875);
DISPLAY INVISIBLE (-16225 5875);
FORCEPROP 1 LAST OFFPAGE TRUE
J 0
(-15900 5750);
DISPLAY 0.872340 (-15900 5750);
PAINT GREEN (-15900 5750);
DISPLAY INVISIBLE (-15900 5750);
FORCEPROP 1 LAST COMMENT_BODY TRUE
J 0
(-16125 5800);
DISPLAY 0.872340 (-16125 5800);
PAINT PEACH (-16125 5800);
DISPLAY INVISIBLE (-16125 5800);
FORCEPROP 2 LAST PATH I4
J 0
(-16175 5950);
DISPLAY 0.680851 (-16175 5950);
DISPLAY INVISIBLE (-16175 5950);
FORCEADD UNIVERSAL_GND..1
(-12925 4625);
FORCEPROP 3 LASTPIN (-12925 4675) SIG_NAME GND\g
J 0
(-12915 4685);
DISPLAY 0.659574 (-12915 4685);
PAINT MONO (-12915 4685);
DISPLAY INVISIBLE (-12915 4685);
FORCEPROP 2 LAST CDS_LIB pure_quanta_power
J 0
(-12925 4625);
DISPLAY INVISIBLE (-12925 4625);
FORCEPROP 1 LAST HDL_POWER GND
J 1
(-12900 4550);
DISPLAY 0.702128 (-12900 4550);
PAINT GREEN (-12900 4550);
DISPLAY INVISIBLE (-12900 4550);
FORCEPROP 1 LAST PATH I40
J 0
(-12850 4625);
DISPLAY 0.872340 (-12850 4625);
PAINT AQUA (-12850 4625);
DISPLAY INVISIBLE (-12850 4625);
FORCEADD UNIVERSAL_GND..1
(-11200 4700);
FORCEPROP 3 LASTPIN (-11200 4750) SIG_NAME GND\g
J 0
(-11190 4760);
DISPLAY 0.659574 (-11190 4760);
PAINT MONO (-11190 4760);
DISPLAY INVISIBLE (-11190 4760);
FORCEPROP 2 LAST CDS_LIB pure_quanta_power
J 0
(-11200 4700);
DISPLAY INVISIBLE (-11200 4700);
FORCEPROP 1 LAST HDL_POWER GND
J 1
(-11175 4625);
DISPLAY 0.702128 (-11175 4625);
PAINT GREEN (-11175 4625);
DISPLAY INVISIBLE (-11175 4625);
FORCEPROP 1 LAST PATH I41
J 0
(-11125 4700);
DISPLAY 0.872340 (-11125 4700);
PAINT AQUA (-11125 4700);
DISPLAY INVISIBLE (-11125 4700);
FORCEADD Q_RES..1
R 2
(-10300 6625);
FORCEPROP 1 LAST LOCATION R6026
J 2
(-10100 6625);
DISPLAY 0.489362 (-10100 6625);
PAINT SKYBLUE (-10100 6625);
FORCEPROP 0 LAST $SEC 1
J 0
(-10100 6650);
DISPLAY 0.680851 (-10100 6650);
PAINT MONO (-10100 6650);
DISPLAY INVISIBLE (-10100 6650);
FORCEPROP 0 LAST CDS_SEC 1
J 0
(-10100 6650);
DISPLAY 0.680851 (-10100 6650);
DISPLAY INVISIBLE (-10100 6650);
FORCEPROP 1 LASTPIN (-10200 6625) $PN 1
J 2
(-10212 6637);
DISPLAY 0.787234 (-10212 6637);
PAINT MONO (-10212 6637);
FORCEPROP 1 LASTPIN (-10400 6625) $PN 2
J 2
(-10362 6637);
DISPLAY 0.787234 (-10362 6637);
PAINT MONO (-10362 6637);
FORCEPROP 1 LAST VALUE 0
J 0
(-10450 6625);
DISPLAY 0.489362 (-10450 6625);
PAINT SKYBLUE (-10450 6625);
FORCEPROP 2 LAST CDS_LIB pure_quanta
J 0
(-10300 6625);
DISPLAY INVISIBLE (-10300 6625);
FORCEPROP 2 LAST BOM_COST MEM
J 0
(-10325 6775);
DISPLAY 0.744681 (-10325 6775);
PAINT WHITE (-10325 6775);
DISPLAY INVISIBLE (-10325 6775);
FORCEPROP 1 LAST WATTAGE 1/16W
J 0
(-10225 6550);
DISPLAY 0.489362 (-10225 6550);
PAINT SKYBLUE (-10225 6550);
DISPLAY INVISIBLE (-10225 6550);
FORCEPROP 1 LAST MATERIAL CHIP
J 0
(-10475 6600);
DISPLAY 0.489362 (-10475 6600);
PAINT SKYBLUE (-10475 6600);
DISPLAY INVISIBLE (-10475 6600);
FORCEPROP 1 LAST TOLERANCE 5%
J 2
(-10175 6600);
DISPLAY 0.489362 (-10175 6600);
PAINT SKYBLUE (-10175 6600);
DISPLAY INVISIBLE (-10175 6600);
FORCEPROP 1 LAST PACK_TYPE 0402LF
J 0
(-10475 6550);
DISPLAY 0.489362 (-10475 6550);
PAINT SKYBLUE (-10475 6550);
DISPLAY INVISIBLE (-10475 6550);
FORCEPROP 1 LAST PATH I42
J 2
(-10250 6775);
DISPLAY 0.978723 (-10250 6775);
PAINT WHITE (-10250 6775);
DISPLAY INVISIBLE (-10250 6775);
FORCEPROP 1 LAST PART_NUMBER CS00002JB13
J 0
(-10400 6675);
DISPLAY 0.489362 (-10400 6675);
PAINT SKYBLUE (-10400 6675);
DISPLAY INVISIBLE (-10400 6675);
FORCEADD Q_RES..1
R 2
(-10300 6675);
FORCEPROP 1 LAST LOCATION R6025
J 2
(-10100 6675);
DISPLAY 0.489362 (-10100 6675);
PAINT SKYBLUE (-10100 6675);
FORCEPROP 0 LAST $SEC 1
J 0
(-10100 6700);
DISPLAY 0.680851 (-10100 6700);
PAINT MONO (-10100 6700);
DISPLAY INVISIBLE (-10100 6700);
FORCEPROP 0 LAST CDS_SEC 1
J 0
(-10100 6700);
DISPLAY 0.680851 (-10100 6700);
DISPLAY INVISIBLE (-10100 6700);
FORCEPROP 1 LASTPIN (-10200 6675) $PN 1
J 2
(-10212 6687);
DISPLAY 0.787234 (-10212 6687);
PAINT MONO (-10212 6687);
FORCEPROP 1 LASTPIN (-10400 6675) $PN 2
J 2
(-10362 6687);
DISPLAY 0.787234 (-10362 6687);
PAINT MONO (-10362 6687);
FORCEPROP 1 LAST VALUE 0
J 0
(-10450 6675);
DISPLAY 0.489362 (-10450 6675);
PAINT SKYBLUE (-10450 6675);
FORCEPROP 2 LAST CDS_LIB pure_quanta
J 0
(-10300 6675);
DISPLAY INVISIBLE (-10300 6675);
FORCEPROP 2 LAST BOM_COST MEM
J 0
(-10325 6825);
DISPLAY 0.744681 (-10325 6825);
PAINT WHITE (-10325 6825);
DISPLAY INVISIBLE (-10325 6825);
FORCEPROP 1 LAST WATTAGE 1/16W
J 0
(-10225 6600);
DISPLAY 0.489362 (-10225 6600);
PAINT SKYBLUE (-10225 6600);
DISPLAY INVISIBLE (-10225 6600);
FORCEPROP 1 LAST MATERIAL CHIP
J 0
(-10475 6650);
DISPLAY 0.489362 (-10475 6650);
PAINT SKYBLUE (-10475 6650);
DISPLAY INVISIBLE (-10475 6650);
FORCEPROP 1 LAST TOLERANCE 5%
J 2
(-10175 6650);
DISPLAY 0.489362 (-10175 6650);
PAINT SKYBLUE (-10175 6650);
DISPLAY INVISIBLE (-10175 6650);
FORCEPROP 1 LAST PACK_TYPE 0402LF
J 0
(-10475 6600);
DISPLAY 0.489362 (-10475 6600);
PAINT SKYBLUE (-10475 6600);
DISPLAY INVISIBLE (-10475 6600);
FORCEPROP 1 LAST PATH I43
J 2
(-10250 6825);
DISPLAY 0.978723 (-10250 6825);
PAINT WHITE (-10250 6825);
DISPLAY INVISIBLE (-10250 6825);
FORCEPROP 1 LAST PART_NUMBER CS00002JB13
J 0
(-10400 6725);
DISPLAY 0.489362 (-10400 6725);
PAINT SKYBLUE (-10400 6725);
DISPLAY INVISIBLE (-10400 6725);
FORCEADD OFFPAGE..4
(-10000 5575);
FORCEPROP 2 LAST $XR0 180 
J 0
(-9814 5575);
DISPLAY 0.638298 (-9814 5575);
PAINT MONO (-9814 5575);
FORCEPROP 2 LAST CDS_LIB standard
J 0
(-10000 5575);
DISPLAY INVISIBLE (-10000 5575);
FORCEPROP 1 LAST OFFPAGE TRUE
J 0
(-9675 5450);
DISPLAY 0.872340 (-9675 5450);
PAINT GREEN (-9675 5450);
DISPLAY INVISIBLE (-9675 5450);
FORCEPROP 1 LAST COMMENT_BODY TRUE
J 0
(-10025 5475);
DISPLAY 0.872340 (-10025 5475);
PAINT PEACH (-10025 5475);
DISPLAY INVISIBLE (-10025 5475);
FORCEPROP 2 LAST PATH I46
J 0
(-9825 5650);
DISPLAY 0.680851 (-9825 5650);
DISPLAY INVISIBLE (-9825 5650);
FORCEADD OFFPAGE..4
(-10000 5525);
FORCEPROP 2 LAST $XR0 180 
J 0
(-9814 5525);
DISPLAY 0.638298 (-9814 5525);
PAINT MONO (-9814 5525);
FORCEPROP 2 LAST CDS_LIB standard
J 0
(-10000 5525);
DISPLAY INVISIBLE (-10000 5525);
FORCEPROP 1 LAST OFFPAGE TRUE
J 0
(-9675 5400);
DISPLAY 0.872340 (-9675 5400);
PAINT GREEN (-9675 5400);
DISPLAY INVISIBLE (-9675 5400);
FORCEPROP 1 LAST COMMENT_BODY TRUE
J 0
(-10025 5425);
DISPLAY 0.872340 (-10025 5425);
PAINT PEACH (-10025 5425);
DISPLAY INVISIBLE (-10025 5425);
FORCEPROP 2 LAST PATH I47
J 0
(-9825 5600);
DISPLAY 0.680851 (-9825 5600);
DISPLAY INVISIBLE (-9825 5600);
FORCEADD OFFPAGE..3
(-10000 5675);
FORCEPROP 2 LAST $XR0 180 
J 0
(-9786 5675);
DISPLAY 0.638298 (-9786 5675);
PAINT MONO (-9786 5675);
FORCEPROP 2 LAST CDS_LIB standard
J 0
(-10000 5675);
PAINT MONO (-10000 5675);
DISPLAY INVISIBLE (-10000 5675);
FORCEPROP 1 LAST OFFPAGE TRUE
J 0
(-9675 5550);
DISPLAY 0.872340 (-9675 5550);
PAINT GREEN (-9675 5550);
DISPLAY INVISIBLE (-9675 5550);
FORCEPROP 1 LAST COMMENT_BODY TRUE
J 0
(-10050 5575);
DISPLAY 0.872340 (-10050 5575);
PAINT PEACH (-10050 5575);
DISPLAY INVISIBLE (-10050 5575);
FORCEPROP 2 LAST PATH I48
J 0
(-9800 5750);
DISPLAY 0.680851 (-9800 5750);
DISPLAY INVISIBLE (-9800 5750);
FORCEADD OFFPAGE..3
(-10000 5725);
FORCEPROP 2 LAST $XR0 180 
J 0
(-9786 5725);
DISPLAY 0.638298 (-9786 5725);
PAINT MONO (-9786 5725);
FORCEPROP 2 LAST CDS_LIB standard
J 0
(-10000 5725);
PAINT MONO (-10000 5725);
DISPLAY INVISIBLE (-10000 5725);
FORCEPROP 1 LAST OFFPAGE TRUE
J 0
(-9675 5600);
DISPLAY 0.872340 (-9675 5600);
PAINT GREEN (-9675 5600);
DISPLAY INVISIBLE (-9675 5600);
FORCEPROP 1 LAST COMMENT_BODY TRUE
J 0
(-10050 5625);
DISPLAY 0.872340 (-10050 5625);
PAINT PEACH (-10050 5625);
DISPLAY INVISIBLE (-10050 5625);
FORCEPROP 2 LAST PATH I49
J 0
(-9800 5800);
DISPLAY 0.680851 (-9800 5800);
DISPLAY INVISIBLE (-9800 5800);
FORCEADD OFFPAGE..1
(-16225 5775);
FORCEPROP 2 LAST $XR0 80 
J 0
(-16446 5775);
DISPLAY 0.638298 (-16446 5775);
PAINT MONO (-16446 5775);
FORCEPROP 2 LAST CDS_LIB standard
J 0
(-16225 5775);
DISPLAY INVISIBLE (-16225 5775);
FORCEPROP 1 LAST OFFPAGE TRUE
J 0
(-15900 5650);
DISPLAY 0.872340 (-15900 5650);
PAINT GREEN (-15900 5650);
DISPLAY INVISIBLE (-15900 5650);
FORCEPROP 1 LAST COMMENT_BODY TRUE
J 0
(-16100 5675);
DISPLAY 0.872340 (-16100 5675);
PAINT PEACH (-16100 5675);
DISPLAY INVISIBLE (-16100 5675);
FORCEPROP 2 LAST PATH I5
J 0
(-16175 5850);
DISPLAY 0.680851 (-16175 5850);
DISPLAY INVISIBLE (-16175 5850);
FORCEADD Q_RES..1
(-9525 5125);
FORCEPROP 1 LAST LOCATION R3254
J 0
(-9750 5125);
DISPLAY 0.638298 (-9750 5125);
FORCEPROP 0 LAST $SEC 1
J 0
(-9275 5300);
DISPLAY 0.680851 (-9275 5300);
PAINT MONO (-9275 5300);
DISPLAY INVISIBLE (-9275 5300);
FORCEPROP 0 LAST CDS_SEC 1
J 0
(-9275 5300);
DISPLAY 1.021277 (-9275 5300);
DISPLAY INVISIBLE (-9275 5300);
FORCEPROP 1 LASTPIN (-9625 5125) $PN 1
J 0
(-9613 5137);
DISPLAY 0.787234 (-9613 5137);
PAINT MONO (-9613 5137);
FORCEPROP 1 LASTPIN (-9425 5125) $PN 2
J 0
(-9463 5137);
DISPLAY 0.787234 (-9463 5137);
PAINT MONO (-9463 5137);
FORCEPROP 1 LAST MATERIAL EMPTY
J 0
(-9275 5125);
DISPLAY 0.638298 (-9275 5125);
PAINT RED (-9275 5125);
FORCEPROP 1 LAST PACK_TYPE 0402LF
J 0
(-9700 5000);
DISPLAY 0.638298 (-9700 5000);
FORCEPROP 1 LAST WATTAGE 1/16W
J 2
(-9325 5000);
DISPLAY 0.638298 (-9325 5000);
FORCEPROP 1 LAST VALUE 0
J 2
(-9375 5125);
DISPLAY 0.638298 (-9375 5125);
FORCEPROP 1 LAST TOLERANCE 5%
J 0
(-9350 5125);
DISPLAY 0.638298 (-9350 5125);
FORCEPROP 2 LAST CDS_LIB pure_quanta
J 0
(-9525 5125);
DISPLAY INVISIBLE (-9525 5125);
FORCEPROP 1 LAST PATH I50
J 0
(-9575 5275);
DISPLAY 0.978723 (-9575 5275);
PAINT WHITE (-9575 5275);
DISPLAY INVISIBLE (-9575 5275);
FORCEPROP 1 LAST PART_NUMBER CS00002JB13
J 0
(-9700 4950);
DISPLAY 0.638298 (-9700 4950);
DISPLAY INVISIBLE (-9700 4950);
FORCEADD OFFPAGE..3
(-10000 5825);
FORCEPROP 2 LAST $XR0 29 
J 0
(-9786 5825);
DISPLAY 0.638298 (-9786 5825);
PAINT MONO (-9786 5825);
FORCEPROP 2 LAST CDS_LIB standard
J 0
(-10000 5825);
PAINT MONO (-10000 5825);
DISPLAY INVISIBLE (-10000 5825);
FORCEPROP 1 LAST OFFPAGE TRUE
J 0
(-9675 5700);
DISPLAY 0.872340 (-9675 5700);
PAINT GREEN (-9675 5700);
DISPLAY INVISIBLE (-9675 5700);
FORCEPROP 1 LAST COMMENT_BODY TRUE
J 0
(-10050 5725);
DISPLAY 0.872340 (-10050 5725);
PAINT PEACH (-10050 5725);
DISPLAY INVISIBLE (-10050 5725);
FORCEPROP 2 LAST PATH I51
J 0
(-9800 5900);
DISPLAY 0.680851 (-9800 5900);
DISPLAY INVISIBLE (-9800 5900);
FORCEADD OFFPAGE..3
(-10000 5875);
FORCEPROP 2 LAST $XR0 29 
J 0
(-9786 5875);
DISPLAY 0.638298 (-9786 5875);
PAINT MONO (-9786 5875);
FORCEPROP 2 LAST CDS_LIB standard
J 0
(-10000 5875);
PAINT MONO (-10000 5875);
DISPLAY INVISIBLE (-10000 5875);
FORCEPROP 1 LAST OFFPAGE TRUE
J 0
(-9675 5750);
DISPLAY 0.872340 (-9675 5750);
PAINT GREEN (-9675 5750);
DISPLAY INVISIBLE (-9675 5750);
FORCEPROP 1 LAST COMMENT_BODY TRUE
J 0
(-10050 5775);
DISPLAY 0.872340 (-10050 5775);
PAINT PEACH (-10050 5775);
DISPLAY INVISIBLE (-10050 5775);
FORCEPROP 2 LAST PATH I52
J 0
(-9800 5950);
DISPLAY 0.680851 (-9800 5950);
DISPLAY INVISIBLE (-9800 5950);
FORCEADD OFFPAGE..3
(-10000 5975);
FORCEPROP 2 LAST $XR0 235 
J 0
(-9786 5975);
DISPLAY 0.638298 (-9786 5975);
PAINT MONO (-9786 5975);
FORCEPROP 2 LAST CDS_LIB standard
J 0
(-10000 5975);
PAINT MONO (-10000 5975);
DISPLAY INVISIBLE (-10000 5975);
FORCEPROP 1 LAST OFFPAGE TRUE
J 0
(-9675 5850);
DISPLAY 0.872340 (-9675 5850);
PAINT GREEN (-9675 5850);
DISPLAY INVISIBLE (-9675 5850);
FORCEPROP 1 LAST COMMENT_BODY TRUE
J 0
(-10050 5875);
DISPLAY 0.872340 (-10050 5875);
PAINT PEACH (-10050 5875);
DISPLAY INVISIBLE (-10050 5875);
FORCEPROP 2 LAST PATH I53
J 0
(-9800 6050);
DISPLAY 0.680851 (-9800 6050);
DISPLAY INVISIBLE (-9800 6050);
FORCEADD OFFPAGE..3
(-10000 6025);
FORCEPROP 2 LAST $XR0 235 
J 0
(-9786 6025);
DISPLAY 0.638298 (-9786 6025);
PAINT MONO (-9786 6025);
FORCEPROP 2 LAST CDS_LIB standard
J 0
(-10000 6025);
PAINT MONO (-10000 6025);
DISPLAY INVISIBLE (-10000 6025);
FORCEPROP 1 LAST OFFPAGE TRUE
J 0
(-9675 5900);
DISPLAY 0.872340 (-9675 5900);
PAINT GREEN (-9675 5900);
DISPLAY INVISIBLE (-9675 5900);
FORCEPROP 1 LAST COMMENT_BODY TRUE
J 0
(-10050 5925);
DISPLAY 0.872340 (-10050 5925);
PAINT PEACH (-10050 5925);
DISPLAY INVISIBLE (-10050 5925);
FORCEPROP 2 LAST PATH I54
J 0
(-9800 6100);
DISPLAY 0.680851 (-9800 6100);
DISPLAY INVISIBLE (-9800 6100);
FORCEADD OFFPAGE..4
(-9375 6625);
FORCEPROP 2 LAST $XR0 80 
J 0
(-9189 6625);
DISPLAY 0.638298 (-9189 6625);
PAINT MONO (-9189 6625);
FORCEPROP 2 LAST $XR1 151 
J 0
(-9099 6625);
DISPLAY 0.638298 (-9099 6625);
PAINT MONO (-9099 6625);
FORCEPROP 2 LAST CDS_LIB standard
J 0
(-9375 6625);
PAINT MONO (-9375 6625);
DISPLAY INVISIBLE (-9375 6625);
FORCEPROP 1 LAST OFFPAGE TRUE
J 0
(-9050 6500);
DISPLAY 0.872340 (-9050 6500);
PAINT GREEN (-9050 6500);
DISPLAY INVISIBLE (-9050 6500);
FORCEPROP 1 LAST COMMENT_BODY TRUE
J 0
(-9400 6525);
DISPLAY 0.872340 (-9400 6525);
PAINT PEACH (-9400 6525);
DISPLAY INVISIBLE (-9400 6525);
FORCEPROP 2 LAST PATH I55
J 0
(-9200 6700);
DISPLAY 0.680851 (-9200 6700);
DISPLAY INVISIBLE (-9200 6700);
FORCEADD OFFPAGE..2
(-9375 6675);
FORCEPROP 2 LAST $XR1 80 
J 0
(-9066 6675);
DISPLAY 0.638298 (-9066 6675);
PAINT MONO (-9066 6675);
FORCEPROP 2 LAST $XR0 151 
J 0
(-9186 6675);
DISPLAY 0.638298 (-9186 6675);
PAINT MONO (-9186 6675);
FORCEPROP 2 LAST CDS_LIB standard
J 0
(-9375 6675);
PAINT MONO (-9375 6675);
DISPLAY INVISIBLE (-9375 6675);
FORCEPROP 1 LAST OFFPAGE TRUE
J 0
(-9050 6550);
DISPLAY 0.872340 (-9050 6550);
PAINT GREEN (-9050 6550);
DISPLAY INVISIBLE (-9050 6550);
FORCEPROP 1 LAST COMMENT_BODY TRUE
J 0
(-9420 6580);
DISPLAY 0.872340 (-9420 6580);
PAINT PEACH (-9420 6580);
DISPLAY INVISIBLE (-9420 6580);
FORCEPROP 2 LAST PATH I56
J 0
(-9200 6750);
DISPLAY 0.680851 (-9200 6750);
DISPLAY INVISIBLE (-9200 6750);
FORCEADD OFFPAGE..4
(-8400 5125);
FORCEPROP 2 LAST $XR1 85 
J 0
(-8094 5125);
DISPLAY 0.638298 (-8094 5125);
PAINT MONO (-8094 5125);
FORCEPROP 2 LAST $XR0 144 
J 0
(-8214 5125);
DISPLAY 0.638298 (-8214 5125);
PAINT MONO (-8214 5125);
FORCEPROP 2 LAST CDS_LIB standard
J 0
(-8400 5125);
DISPLAY INVISIBLE (-8400 5125);
FORCEPROP 1 LAST OFFPAGE TRUE
J 0
(-8075 5000);
DISPLAY 0.872340 (-8075 5000);
PAINT GREEN (-8075 5000);
DISPLAY INVISIBLE (-8075 5000);
FORCEPROP 1 LAST COMMENT_BODY TRUE
J 0
(-8425 5025);
DISPLAY 0.872340 (-8425 5025);
PAINT PEACH (-8425 5025);
DISPLAY INVISIBLE (-8425 5025);
FORCEPROP 2 LAST PATH I57
J 0
(-8225 5200);
DISPLAY 0.680851 (-8225 5200);
DISPLAY INVISIBLE (-8225 5200);
FORCEADD UNIVERSAL_GND..1
(-8500 6475);
FORCEPROP 3 LASTPIN (-8500 6525) SIG_NAME GND\g
J 0
(-8490 6535);
DISPLAY 0.659574 (-8490 6535);
PAINT MONO (-8490 6535);
DISPLAY INVISIBLE (-8490 6535);
FORCEPROP 2 LAST CDS_LIB pure_quanta_power
R 3
J 0
(-8500 6475);
DISPLAY INVISIBLE (-8500 6475);
FORCEPROP 1 LAST HDL_POWER GND
J 1
(-8475 6400);
DISPLAY 0.872340 (-8475 6400);
PAINT GREEN (-8475 6400);
DISPLAY INVISIBLE (-8475 6400);
FORCEPROP 1 LAST PATH I58
J 0
(-8425 6475);
DISPLAY 0.872340 (-8425 6475);
PAINT AQUA (-8425 6475);
DISPLAY INVISIBLE (-8425 6475);
FORCEADD OFFPAGE..5
(-16225 6075);
FORCEPROP 2 LAST $XR0 151 
J 0
(-16480 6075);
DISPLAY 0.638298 (-16480 6075);
PAINT MONO (-16480 6075);
FORCEPROP 2 LAST $XR1 172 
J 0
(-16600 6075);
DISPLAY 0.638298 (-16600 6075);
PAINT MONO (-16600 6075);
FORCEPROP 2 LAST CDS_LIB standard
J 0
(-16225 6075);
PAINT MONO (-16225 6075);
DISPLAY INVISIBLE (-16225 6075);
FORCEPROP 1 LAST OFFPAGE TRUE
J 0
(-15900 5950);
DISPLAY 0.872340 (-15900 5950);
PAINT GREEN (-15900 5950);
DISPLAY INVISIBLE (-15900 5950);
FORCEPROP 1 LAST COMMENT_BODY TRUE
J 0
(-16125 6000);
DISPLAY 0.872340 (-16125 6000);
PAINT PEACH (-16125 6000);
DISPLAY INVISIBLE (-16125 6000);
FORCEPROP 2 LAST PATH I6
J 0
(-16175 6150);
DISPLAY 0.680851 (-16175 6150);
DISPLAY INVISIBLE (-16175 6150);
FORCEADD Q_RES..1
(-14950 6725);
FORCEPROP 1 LAST LOCATION R2415
J 0
(-15175 6725);
DISPLAY 0.638298 (-15175 6725);
FORCEPROP 0 LAST $SEC 1
J 0
(-15175 6775);
DISPLAY 0.680851 (-15175 6775);
PAINT MONO (-15175 6775);
DISPLAY INVISIBLE (-15175 6775);
FORCEPROP 0 LAST CDS_SEC 1
J 0
(-15175 6775);
DISPLAY 1.021277 (-15175 6775);
DISPLAY INVISIBLE (-15175 6775);
FORCEPROP 1 LASTPIN (-15050 6725) $PN 1
J 0
(-15038 6737);
DISPLAY 0.787234 (-15038 6737);
PAINT MONO (-15038 6737);
FORCEPROP 1 LASTPIN (-14850 6725) $PN 2
J 0
(-14888 6737);
DISPLAY 0.787234 (-14888 6737);
PAINT MONO (-14888 6737);
FORCEPROP 1 LAST MATERIAL CHIP
J 0
(-14650 6725);
DISPLAY 0.510638 (-14650 6725);
FORCEPROP 1 LAST TOLERANCE 1%
J 0
(-14725 6725);
DISPLAY 0.510638 (-14725 6725);
FORCEPROP 1 LAST VALUE 33.2
J 2
(-14750 6725);
DISPLAY 0.510638 (-14750 6725);
FORCEPROP 1 LAST WATTAGE 1/16W
J 2
(-14850 6825);
DISPLAY 0.404255 (-14850 6825);
DISPLAY INVISIBLE (-14850 6825);
FORCEPROP 1 LAST PACK_TYPE 0402LF
J 0
(-15075 6825);
DISPLAY 0.404255 (-15075 6825);
DISPLAY INVISIBLE (-15075 6825);
FORCEPROP 2 LAST CDS_LIB pure_quanta
J 0
(-14950 6725);
DISPLAY INVISIBLE (-14950 6725);
FORCEPROP 1 LAST PATH I60
J 0
(-15000 6875);
DISPLAY 0.978723 (-15000 6875);
PAINT WHITE (-15000 6875);
DISPLAY INVISIBLE (-15000 6875);
FORCEPROP 1 LAST PART_NUMBER CS03322FB03
J 0
(-15075 6775);
DISPLAY 0.404255 (-15075 6775);
DISPLAY INVISIBLE (-15075 6775);
FORCEADD OFFPAGE..6
(-16200 7025);
FORCEPROP 2 LAST $XR1 249 
J 0
(-16600 7025);
DISPLAY 0.638298 (-16600 7025);
PAINT MONO (-16600 7025);
FORCEPROP 2 LAST $XR0 151 
J 0
(-16480 7025);
DISPLAY 0.638298 (-16480 7025);
PAINT MONO (-16480 7025);
FORCEPROP 2 LAST CDS_LIB standard
J 0
(-16200 7025);
DISPLAY INVISIBLE (-16200 7025);
FORCEPROP 1 LAST OFFPAGE TRUE
J 0
(-15875 6900);
DISPLAY 0.872340 (-15875 6900);
PAINT GREEN (-15875 6900);
DISPLAY INVISIBLE (-15875 6900);
FORCEPROP 1 LAST COMMENT_BODY TRUE
J 0
(-16100 6950);
DISPLAY 0.872340 (-16100 6950);
PAINT PEACH (-16100 6950);
DISPLAY INVISIBLE (-16100 6950);
FORCEPROP 2 LAST PATH I62
J 0
(-16150 7100);
DISPLAY 0.680851 (-16150 7100);
DISPLAY INVISIBLE (-16150 7100);
FORCEADD OFFPAGE..1
(-16200 7325);
FORCEPROP 2 LAST $XR0 151 
J 0
(-16482 7325);
DISPLAY 0.638298 (-16482 7325);
PAINT MONO (-16482 7325);
FORCEPROP 2 LAST CDS_LIB standard
J 0
(-16200 7325);
PAINT MONO (-16200 7325);
DISPLAY INVISIBLE (-16200 7325);
FORCEPROP 1 LAST OFFPAGE TRUE
J 0
(-15875 7200);
DISPLAY 0.872340 (-15875 7200);
DISPLAY INVISIBLE (-15875 7200);
FORCEPROP 1 LAST COMMENT_BODY TRUE
J 0
(-16075 7225);
DISPLAY 0.872340 (-16075 7225);
PAINT GREEN (-16075 7225);
DISPLAY INVISIBLE (-16075 7225);
FORCEPROP 2 LAST PATH I63
J 0
(-16150 7400);
DISPLAY 0.680851 (-16150 7400);
DISPLAY INVISIBLE (-16150 7400);
FORCEADD OFFPAGE..2
R 2
(-16250 8175);
FORCEPROP 2 LAST $XR1 248 
J 0
(-16625 8175);
DISPLAY 0.638298 (-16625 8175);
PAINT MONO (-16625 8175);
FORCEPROP 2 LAST $XR0 151 
J 0
(-16505 8175);
DISPLAY 0.638298 (-16505 8175);
PAINT MONO (-16505 8175);
FORCEPROP 2 LAST CDS_LIB standard
J 2
(-16250 8175);
DISPLAY INVISIBLE (-16250 8175);
FORCEPROP 1 LAST OFFPAGE TRUE
J 2
(-16575 8050);
DISPLAY 0.872340 (-16575 8050);
DISPLAY INVISIBLE (-16575 8050);
FORCEPROP 1 LAST COMMENT_BODY TRUE
J 2
(-16205 8080);
DISPLAY 0.872340 (-16205 8080);
PAINT GREEN (-16205 8080);
DISPLAY INVISIBLE (-16205 8080);
FORCEPROP 2 LAST PATH I67
J 2
(-16300 8250);
DISPLAY 0.680851 (-16300 8250);
DISPLAY INVISIBLE (-16300 8250);
FORCEADD OFFPAGE..6
(-16225 8125);
FORCEPROP 2 LAST $XR1 248 
J 0
(-16625 8125);
DISPLAY 0.638298 (-16625 8125);
PAINT MONO (-16625 8125);
FORCEPROP 2 LAST $XR0 151 
J 0
(-16505 8125);
DISPLAY 0.638298 (-16505 8125);
PAINT MONO (-16505 8125);
FORCEPROP 2 LAST CDS_LIB standard
J 0
(-16225 8125);
DISPLAY INVISIBLE (-16225 8125);
FORCEPROP 1 LAST OFFPAGE TRUE
J 0
(-15900 8000);
DISPLAY 0.872340 (-15900 8000);
PAINT GREEN (-15900 8000);
DISPLAY INVISIBLE (-15900 8000);
FORCEPROP 1 LAST COMMENT_BODY TRUE
J 0
(-16125 8050);
DISPLAY 0.872340 (-16125 8050);
PAINT PEACH (-16125 8050);
DISPLAY INVISIBLE (-16125 8050);
FORCEPROP 2 LAST PATH I68
J 0
(-16175 8200);
DISPLAY 0.680851 (-16175 8200);
DISPLAY INVISIBLE (-16175 8200);
FORCEADD OFFPAGE..5
(-16225 6175);
FORCEPROP 2 LAST $XR0 83 
J 0
(-16449 6175);
DISPLAY 0.638298 (-16449 6175);
PAINT MONO (-16449 6175);
FORCEPROP 2 LAST $XR1 80 
J 0
(-16539 6175);
DISPLAY 0.638298 (-16539 6175);
PAINT MONO (-16539 6175);
FORCEPROP 2 LAST CDS_LIB standard
J 0
(-16225 6175);
PAINT MONO (-16225 6175);
DISPLAY INVISIBLE (-16225 6175);
FORCEPROP 1 LAST OFFPAGE TRUE
J 0
(-15900 6050);
DISPLAY 0.872340 (-15900 6050);
PAINT GREEN (-15900 6050);
DISPLAY INVISIBLE (-15900 6050);
FORCEPROP 1 LAST COMMENT_BODY TRUE
J 0
(-16125 6100);
DISPLAY 0.872340 (-16125 6100);
PAINT PEACH (-16125 6100);
DISPLAY INVISIBLE (-16125 6100);
FORCEPROP 2 LAST PATH I7
J 0
(-16175 6250);
DISPLAY 0.680851 (-16175 6250);
DISPLAY INVISIBLE (-16175 6250);
FORCEADD OFFPAGE..6
(-16225 8425);
FORCEPROP 2 LAST $XR0 253 
J 0
(-16505 8425);
DISPLAY 0.638298 (-16505 8425);
PAINT MONO (-16505 8425);
FORCEPROP 2 LAST CDS_LIB standard
J 0
(-16225 8425);
DISPLAY INVISIBLE (-16225 8425);
FORCEPROP 1 LAST OFFPAGE TRUE
J 0
(-15900 8300);
DISPLAY 0.872340 (-15900 8300);
PAINT GREEN (-15900 8300);
DISPLAY INVISIBLE (-15900 8300);
FORCEPROP 1 LAST COMMENT_BODY TRUE
J 0
(-16125 8350);
DISPLAY 0.872340 (-16125 8350);
PAINT PEACH (-16125 8350);
DISPLAY INVISIBLE (-16125 8350);
FORCEPROP 2 LAST PATH I72
J 0
(-16175 8500);
DISPLAY 0.680851 (-16175 8500);
DISPLAY INVISIBLE (-16175 8500);
FORCEADD OFFPAGE..6
(-16225 8525);
FORCEPROP 2 LAST $XR1 160 
J 0
(-16625 8525);
DISPLAY 0.638298 (-16625 8525);
PAINT MONO (-16625 8525);
FORCEPROP 2 LAST $XR0 151 
J 0
(-16505 8525);
DISPLAY 0.638298 (-16505 8525);
PAINT MONO (-16505 8525);
FORCEPROP 2 LAST CDS_LIB standard
J 0
(-16225 8525);
DISPLAY INVISIBLE (-16225 8525);
FORCEPROP 1 LAST OFFPAGE TRUE
J 0
(-15900 8400);
DISPLAY 0.872340 (-15900 8400);
PAINT GREEN (-15900 8400);
DISPLAY INVISIBLE (-15900 8400);
FORCEPROP 1 LAST COMMENT_BODY TRUE
J 0
(-16125 8450);
DISPLAY 0.872340 (-16125 8450);
PAINT PEACH (-16125 8450);
DISPLAY INVISIBLE (-16125 8450);
FORCEPROP 2 LAST PATH I73
J 0
(-16175 8600);
DISPLAY 0.680851 (-16175 8600);
DISPLAY INVISIBLE (-16175 8600);
FORCEADD OFFPAGE..6
(-16225 8625);
FORCEPROP 2 LAST $XR1 248 
J 0
(-16625 8625);
DISPLAY 0.638298 (-16625 8625);
PAINT MONO (-16625 8625);
FORCEPROP 2 LAST $XR0 151 
J 0
(-16505 8625);
DISPLAY 0.638298 (-16505 8625);
PAINT MONO (-16505 8625);
FORCEPROP 2 LAST CDS_LIB standard
J 0
(-16225 8625);
DISPLAY INVISIBLE (-16225 8625);
FORCEPROP 1 LAST OFFPAGE TRUE
J 0
(-15900 8500);
DISPLAY 0.872340 (-15900 8500);
PAINT GREEN (-15900 8500);
DISPLAY INVISIBLE (-15900 8500);
FORCEPROP 1 LAST COMMENT_BODY TRUE
J 0
(-16125 8550);
DISPLAY 0.872340 (-16125 8550);
PAINT PEACH (-16125 8550);
DISPLAY INVISIBLE (-16125 8550);
FORCEPROP 2 LAST PATH I75
J 0
(-16175 8700);
DISPLAY 0.680851 (-16175 8700);
DISPLAY INVISIBLE (-16175 8700);
FORCEADD OFFPAGE..6
(-15625 8925);
FORCEPROP 2 LAST $XR0 159 
J 0
(-15905 8925);
DISPLAY 0.638298 (-15905 8925);
PAINT MONO (-15905 8925);
FORCEPROP 2 LAST CDS_LIB standard
J 0
(-15625 8925);
DISPLAY INVISIBLE (-15625 8925);
FORCEPROP 1 LAST OFFPAGE TRUE
J 0
(-15300 8800);
DISPLAY 0.872340 (-15300 8800);
PAINT GREEN (-15300 8800);
DISPLAY INVISIBLE (-15300 8800);
FORCEPROP 1 LAST COMMENT_BODY TRUE
J 0
(-15525 8850);
DISPLAY 0.872340 (-15525 8850);
PAINT PEACH (-15525 8850);
DISPLAY INVISIBLE (-15525 8850);
FORCEPROP 2 LAST PATH I77
J 0
(-15575 9000);
DISPLAY 0.680851 (-15575 9000);
DISPLAY INVISIBLE (-15575 9000);
FORCEADD OFFPAGE..6
(-15625 9025);
FORCEPROP 2 LAST $XR0 159 
J 0
(-15905 9025);
DISPLAY 0.638298 (-15905 9025);
PAINT MONO (-15905 9025);
FORCEPROP 2 LAST CDS_LIB standard
J 0
(-15625 9025);
DISPLAY INVISIBLE (-15625 9025);
FORCEPROP 1 LAST OFFPAGE TRUE
J 0
(-15300 8900);
DISPLAY 0.872340 (-15300 8900);
PAINT GREEN (-15300 8900);
DISPLAY INVISIBLE (-15300 8900);
FORCEPROP 1 LAST COMMENT_BODY TRUE
J 0
(-15525 8950);
DISPLAY 0.872340 (-15525 8950);
PAINT PEACH (-15525 8950);
DISPLAY INVISIBLE (-15525 8950);
FORCEPROP 2 LAST PATH I78
J 0
(-15575 9100);
DISPLAY 0.680851 (-15575 9100);
DISPLAY INVISIBLE (-15575 9100);
FORCEADD OFFPAGE..1
(-16225 6125);
FORCEPROP 2 LAST $XR0 85 
J 0
(-16446 6125);
DISPLAY 0.638298 (-16446 6125);
PAINT MONO (-16446 6125);
FORCEPROP 2 LAST CDS_LIB standard
J 0
(-16225 6125);
PAINT MONO (-16225 6125);
DISPLAY INVISIBLE (-16225 6125);
FORCEPROP 1 LAST OFFPAGE TRUE
J 0
(-15900 6000);
DISPLAY 0.872340 (-15900 6000);
PAINT GREEN (-15900 6000);
DISPLAY INVISIBLE (-15900 6000);
FORCEPROP 1 LAST COMMENT_BODY TRUE
J 0
(-16100 6025);
DISPLAY 0.872340 (-16100 6025);
PAINT PEACH (-16100 6025);
DISPLAY INVISIBLE (-16100 6025);
FORCEPROP 2 LAST PATH I8
J 0
(-16175 6200);
DISPLAY 0.680851 (-16175 6200);
DISPLAY INVISIBLE (-16175 6200);
FORCEADD OFFPAGE..6
(-15625 9125);
FORCEPROP 2 LAST $XR0 159 
J 0
(-15905 9125);
DISPLAY 0.638298 (-15905 9125);
PAINT MONO (-15905 9125);
FORCEPROP 2 LAST CDS_LIB standard
J 0
(-15625 9125);
PAINT MONO (-15625 9125);
DISPLAY INVISIBLE (-15625 9125);
FORCEPROP 1 LAST OFFPAGE TRUE
J 0
(-15300 9000);
DISPLAY 0.872340 (-15300 9000);
PAINT GREEN (-15300 9000);
DISPLAY INVISIBLE (-15300 9000);
FORCEPROP 1 LAST COMMENT_BODY TRUE
J 0
(-15525 9050);
DISPLAY 0.872340 (-15525 9050);
PAINT PEACH (-15525 9050);
DISPLAY INVISIBLE (-15525 9050);
FORCEPROP 2 LAST PATH I80
J 0
(-15575 9200);
DISPLAY 0.680851 (-15575 9200);
DISPLAY INVISIBLE (-15575 9200);
FORCEADD OFFPAGE..6
(-15625 9225);
FORCEPROP 2 LAST $XR0 159 
J 0
(-15905 9225);
DISPLAY 0.638298 (-15905 9225);
PAINT MONO (-15905 9225);
FORCEPROP 2 LAST CDS_LIB standard
J 0
(-15625 9225);
PAINT MONO (-15625 9225);
DISPLAY INVISIBLE (-15625 9225);
FORCEPROP 1 LAST OFFPAGE TRUE
J 0
(-15300 9100);
DISPLAY 0.872340 (-15300 9100);
PAINT GREEN (-15300 9100);
DISPLAY INVISIBLE (-15300 9100);
FORCEPROP 1 LAST COMMENT_BODY TRUE
J 0
(-15525 9150);
DISPLAY 0.872340 (-15525 9150);
PAINT PEACH (-15525 9150);
DISPLAY INVISIBLE (-15525 9150);
FORCEPROP 2 LAST PATH I83
J 0
(-15575 9300);
DISPLAY 0.680851 (-15575 9300);
DISPLAY INVISIBLE (-15575 9300);
FORCEADD Q_RES..1
(-14950 7025);
FORCEPROP 1 LAST LOCATION R2414
J 0
(-15175 7025);
DISPLAY 0.638298 (-15175 7025);
FORCEPROP 0 LAST $SEC 1
J 0
(-15175 7075);
DISPLAY 0.680851 (-15175 7075);
PAINT MONO (-15175 7075);
DISPLAY INVISIBLE (-15175 7075);
FORCEPROP 0 LAST CDS_SEC 1
J 0
(-15175 7075);
DISPLAY 1.021277 (-15175 7075);
DISPLAY INVISIBLE (-15175 7075);
FORCEPROP 1 LASTPIN (-15050 7025) $PN 1
J 0
(-15038 7037);
DISPLAY 0.787234 (-15038 7037);
PAINT MONO (-15038 7037);
FORCEPROP 1 LASTPIN (-14850 7025) $PN 2
J 0
(-14888 7037);
DISPLAY 0.787234 (-14888 7037);
PAINT MONO (-14888 7037);
FORCEPROP 1 LAST VALUE 33.2
J 2
(-14750 7025);
DISPLAY 0.510638 (-14750 7025);
FORCEPROP 1 LAST TOLERANCE 1%
J 0
(-14725 7025);
DISPLAY 0.510638 (-14725 7025);
FORCEPROP 1 LAST MATERIAL CHIP
J 0
(-14650 7025);
DISPLAY 0.510638 (-14650 7025);
FORCEPROP 1 LAST PACK_TYPE 0402LF
J 0
(-15075 7125);
DISPLAY 0.404255 (-15075 7125);
DISPLAY INVISIBLE (-15075 7125);
FORCEPROP 1 LAST WATTAGE 1/16W
J 2
(-14850 7125);
DISPLAY 0.404255 (-14850 7125);
DISPLAY INVISIBLE (-14850 7125);
FORCEPROP 2 LAST CDS_LIB pure_quanta
J 0
(-14950 7025);
DISPLAY INVISIBLE (-14950 7025);
FORCEPROP 1 LAST PATH I85
J 0
(-15000 7175);
DISPLAY 0.978723 (-15000 7175);
PAINT WHITE (-15000 7175);
DISPLAY INVISIBLE (-15000 7175);
FORCEPROP 1 LAST PART_NUMBER CS03322FB03
J 0
(-15075 7075);
DISPLAY 0.404255 (-15075 7075);
DISPLAY INVISIBLE (-15075 7075);
FORCEADD Q_RES..1
(-14950 7075);
FORCEPROP 1 LAST LOCATION R2413
J 0
(-15175 7075);
DISPLAY 0.638298 (-15175 7075);
FORCEPROP 0 LAST $SEC 1
J 0
(-15175 7125);
DISPLAY 0.680851 (-15175 7125);
PAINT MONO (-15175 7125);
DISPLAY INVISIBLE (-15175 7125);
FORCEPROP 0 LAST CDS_SEC 1
J 0
(-15175 7125);
DISPLAY 1.021277 (-15175 7125);
DISPLAY INVISIBLE (-15175 7125);
FORCEPROP 1 LASTPIN (-15050 7075) $PN 1
J 0
(-15038 7087);
DISPLAY 0.787234 (-15038 7087);
PAINT MONO (-15038 7087);
FORCEPROP 1 LASTPIN (-14850 7075) $PN 2
J 0
(-14888 7087);
DISPLAY 0.787234 (-14888 7087);
PAINT MONO (-14888 7087);
FORCEPROP 1 LAST VALUE 33.2
J 2
(-14750 7075);
DISPLAY 0.510638 (-14750 7075);
FORCEPROP 1 LAST TOLERANCE 1%
J 0
(-14725 7075);
DISPLAY 0.510638 (-14725 7075);
FORCEPROP 1 LAST MATERIAL CHIP
J 0
(-14650 7075);
DISPLAY 0.510638 (-14650 7075);
FORCEPROP 1 LAST PACK_TYPE 0402LF
J 0
(-15075 7175);
DISPLAY 0.404255 (-15075 7175);
DISPLAY INVISIBLE (-15075 7175);
FORCEPROP 1 LAST WATTAGE 1/16W
J 2
(-14850 7175);
DISPLAY 0.404255 (-14850 7175);
DISPLAY INVISIBLE (-14850 7175);
FORCEPROP 2 LAST CDS_LIB pure_quanta
J 0
(-14950 7075);
DISPLAY INVISIBLE (-14950 7075);
FORCEPROP 1 LAST PATH I86
J 0
(-15000 7225);
DISPLAY 0.978723 (-15000 7225);
PAINT WHITE (-15000 7225);
DISPLAY INVISIBLE (-15000 7225);
FORCEPROP 1 LAST PART_NUMBER CS03322FB03
J 0
(-15075 7125);
DISPLAY 0.404255 (-15075 7125);
DISPLAY INVISIBLE (-15075 7125);
FORCEADD Q_RES..1
(-14925 7325);
FORCEPROP 1 LAST LOCATION R4509
J 0
(-15150 7325);
DISPLAY 0.787234 (-15150 7325);
FORCEPROP 0 LAST $SEC 1
J 0
(-15125 7375);
DISPLAY 0.680851 (-15125 7375);
PAINT MONO (-15125 7375);
DISPLAY INVISIBLE (-15125 7375);
FORCEPROP 0 LAST CDS_SEC 1
J 0
(-15125 7375);
DISPLAY 1.021277 (-15125 7375);
DISPLAY INVISIBLE (-15125 7375);
FORCEPROP 1 LASTPIN (-15025 7325) $PN 1
J 0
(-15013 7337);
DISPLAY 0.787234 (-15013 7337);
PAINT MONO (-15013 7337);
FORCEPROP 1 LASTPIN (-14825 7325) $PN 2
J 0
(-14863 7337);
DISPLAY 0.787234 (-14863 7337);
PAINT MONO (-14863 7337);
FORCEPROP 1 LAST TOLERANCE 1%
J 0
(-14700 7325);
DISPLAY 0.510638 (-14700 7325);
FORCEPROP 1 LAST VALUE 33.2
J 2
(-14725 7325);
DISPLAY 0.510638 (-14725 7325);
FORCEPROP 1 LAST MATERIAL CHIP
J 0
(-14625 7325);
DISPLAY 0.510638 (-14625 7325);
FORCEPROP 2 LAST CDS_LIB pure_quanta
J 0
(-14925 7325);
DISPLAY INVISIBLE (-14925 7325);
FORCEPROP 1 LAST PACK_TYPE 0402LF
J 0
(-15050 7425);
DISPLAY 0.404255 (-15050 7425);
DISPLAY INVISIBLE (-15050 7425);
FORCEPROP 1 LAST WATTAGE 1/16W
J 2
(-14825 7425);
DISPLAY 0.404255 (-14825 7425);
DISPLAY INVISIBLE (-14825 7425);
FORCEPROP 1 LAST PATH I87
J 0
(-14975 7475);
DISPLAY 0.978723 (-14975 7475);
PAINT WHITE (-14975 7475);
DISPLAY INVISIBLE (-14975 7475);
FORCEPROP 1 LAST PART_NUMBER CS03322FB03
J 0
(-15050 7375);
DISPLAY 0.404255 (-15050 7375);
DISPLAY INVISIBLE (-15050 7375);
FORCEADD Q_RES..1
(-14925 7375);
FORCEPROP 1 LAST LOCATION R4508
J 0
(-15150 7375);
DISPLAY 0.787234 (-15150 7375);
FORCEPROP 0 LAST $SEC 1
J 0
(-15125 7425);
DISPLAY 0.680851 (-15125 7425);
PAINT MONO (-15125 7425);
DISPLAY INVISIBLE (-15125 7425);
FORCEPROP 0 LAST CDS_SEC 1
J 0
(-15125 7425);
DISPLAY 1.021277 (-15125 7425);
DISPLAY INVISIBLE (-15125 7425);
FORCEPROP 1 LASTPIN (-15025 7375) $PN 1
J 0
(-15013 7387);
DISPLAY 0.787234 (-15013 7387);
PAINT MONO (-15013 7387);
FORCEPROP 1 LASTPIN (-14825 7375) $PN 2
J 0
(-14863 7387);
DISPLAY 0.787234 (-14863 7387);
PAINT MONO (-14863 7387);
FORCEPROP 1 LAST TOLERANCE 1%
J 0
(-14700 7375);
DISPLAY 0.510638 (-14700 7375);
FORCEPROP 1 LAST MATERIAL CHIP
J 0
(-14625 7375);
DISPLAY 0.510638 (-14625 7375);
FORCEPROP 1 LAST VALUE 33.2
J 2
(-14725 7375);
DISPLAY 0.510638 (-14725 7375);
FORCEPROP 2 LAST CDS_LIB pure_quanta
J 0
(-14925 7375);
DISPLAY INVISIBLE (-14925 7375);
FORCEPROP 1 LAST PACK_TYPE 0402LF
J 0
(-15050 7475);
DISPLAY 0.404255 (-15050 7475);
DISPLAY INVISIBLE (-15050 7475);
FORCEPROP 1 LAST WATTAGE 1/16W
J 2
(-14825 7475);
DISPLAY 0.404255 (-14825 7475);
DISPLAY INVISIBLE (-14825 7475);
FORCEPROP 1 LAST PATH I88
J 0
(-14975 7525);
DISPLAY 0.978723 (-14975 7525);
PAINT WHITE (-14975 7525);
DISPLAY INVISIBLE (-14975 7525);
FORCEPROP 1 LAST PART_NUMBER CS03322FB03
J 0
(-15050 7425);
DISPLAY 0.404255 (-15050 7425);
DISPLAY INVISIBLE (-15050 7425);
FORCEADD OFFPAGE..5
(-16225 6225);
FORCEPROP 2 LAST $XR0 151 
J 0
(-16480 6225);
DISPLAY 0.638298 (-16480 6225);
PAINT MONO (-16480 6225);
FORCEPROP 2 LAST $XR1 80 
J 0
(-16570 6225);
DISPLAY 0.638298 (-16570 6225);
PAINT MONO (-16570 6225);
FORCEPROP 2 LAST CDS_LIB standard
J 0
(-16225 6225);
DISPLAY INVISIBLE (-16225 6225);
FORCEPROP 1 LAST OFFPAGE TRUE
J 0
(-15900 6100);
DISPLAY 0.872340 (-15900 6100);
PAINT GREEN (-15900 6100);
DISPLAY INVISIBLE (-15900 6100);
FORCEPROP 1 LAST COMMENT_BODY TRUE
J 0
(-16125 6150);
DISPLAY 0.872340 (-16125 6150);
PAINT PEACH (-16125 6150);
DISPLAY INVISIBLE (-16125 6150);
FORCEPROP 2 LAST PATH I9
J 0
(-16175 6300);
DISPLAY 0.680851 (-16175 6300);
DISPLAY INVISIBLE (-16175 6300);
FORCEADD OFFPAGE..1
(-14100 6775);
FORCEPROP 2 LAST $XR0 151 
J 0
(-14352 6775);
DISPLAY 0.638298 (-14352 6775);
PAINT MONO (-14352 6775);
FORCEPROP 2 LAST CDS_LIB standard
J 0
(-14100 6775);
DISPLAY INVISIBLE (-14100 6775);
FORCEPROP 1 LAST OFFPAGE TRUE
J 0
(-13775 6650);
DISPLAY 0.872340 (-13775 6650);
PAINT GREEN (-13775 6650);
DISPLAY INVISIBLE (-13775 6650);
FORCEPROP 1 LAST COMMENT_BODY TRUE
J 0
(-13975 6675);
DISPLAY 0.872340 (-13975 6675);
PAINT PEACH (-13975 6675);
DISPLAY INVISIBLE (-13975 6675);
FORCEPROP 2 LAST PATH I91
J 0
(-14050 6850);
DISPLAY 0.680851 (-14050 6850);
DISPLAY INVISIBLE (-14050 6850);
FORCEADD OFFPAGE..6
(-14100 7175);
FORCEPROP 2 LAST $XR1 241 
J 0
(-14500 7175);
DISPLAY 0.638298 (-14500 7175);
PAINT MONO (-14500 7175);
FORCEPROP 2 LAST $XR0 151 
J 0
(-14380 7175);
DISPLAY 0.638298 (-14380 7175);
PAINT MONO (-14380 7175);
FORCEPROP 2 LAST CDS_LIB standard
J 0
(-14100 7175);
DISPLAY INVISIBLE (-14100 7175);
FORCEPROP 1 LAST OFFPAGE TRUE
J 0
(-13775 7050);
DISPLAY 0.872340 (-13775 7050);
PAINT GREEN (-13775 7050);
DISPLAY INVISIBLE (-13775 7050);
FORCEPROP 1 LAST COMMENT_BODY TRUE
J 0
(-14000 7100);
DISPLAY 0.872340 (-14000 7100);
PAINT PEACH (-14000 7100);
DISPLAY INVISIBLE (-14000 7100);
FORCEPROP 2 LAST PATH I92
J 0
(-14400 7225);
DISPLAY 0.680851 (-14400 7225);
DISPLAY INVISIBLE (-14400 7225);
FORCEADD OFFPAGE..6
(-14100 7125);
FORCEPROP 2 LAST $XR1 241 
J 0
(-14500 7125);
DISPLAY 0.638298 (-14500 7125);
PAINT MONO (-14500 7125);
FORCEPROP 2 LAST $XR0 151 
J 0
(-14380 7125);
DISPLAY 0.638298 (-14380 7125);
PAINT MONO (-14380 7125);
FORCEPROP 2 LAST CDS_LIB standard
J 0
(-14100 7125);
PAINT MONO (-14100 7125);
DISPLAY INVISIBLE (-14100 7125);
FORCEPROP 1 LAST OFFPAGE TRUE
J 0
(-13775 7000);
DISPLAY 0.872340 (-13775 7000);
PAINT GREEN (-13775 7000);
DISPLAY INVISIBLE (-13775 7000);
FORCEPROP 1 LAST COMMENT_BODY TRUE
J 0
(-14000 7050);
DISPLAY 0.872340 (-14000 7050);
PAINT PEACH (-14000 7050);
DISPLAY INVISIBLE (-14000 7050);
FORCEPROP 2 LAST PATH I93
J 0
(-14400 7175);
DISPLAY 0.680851 (-14400 7175);
DISPLAY INVISIBLE (-14400 7175);
FORCEADD OFFPAGE..6
(-14100 7525);
FORCEPROP 2 LAST $XR0 251 
J 0
(-14380 7525);
DISPLAY 0.638298 (-14380 7525);
PAINT MONO (-14380 7525);
FORCEPROP 2 LAST CDS_LIB standard
J 0
(-14100 7525);
DISPLAY INVISIBLE (-14100 7525);
FORCEPROP 1 LAST OFFPAGE TRUE
J 0
(-13775 7400);
DISPLAY 0.872340 (-13775 7400);
PAINT GREEN (-13775 7400);
DISPLAY INVISIBLE (-13775 7400);
FORCEPROP 1 LAST COMMENT_BODY TRUE
J 0
(-14000 7450);
DISPLAY 0.872340 (-14000 7450);
PAINT PEACH (-14000 7450);
DISPLAY INVISIBLE (-14000 7450);
FORCEPROP 2 LAST PATH I94
J 0
(-14050 7600);
DISPLAY 0.680851 (-14050 7600);
DISPLAY INVISIBLE (-14050 7600);
FORCEADD OFFPAGE..6
(-14100 7575);
FORCEPROP 2 LAST $XR0 251 
J 0
(-14380 7575);
DISPLAY 0.638298 (-14380 7575);
PAINT MONO (-14380 7575);
FORCEPROP 2 LAST CDS_LIB standard
J 0
(-14100 7575);
DISPLAY INVISIBLE (-14100 7575);
FORCEPROP 1 LAST OFFPAGE TRUE
J 0
(-13775 7450);
DISPLAY 0.872340 (-13775 7450);
PAINT GREEN (-13775 7450);
DISPLAY INVISIBLE (-13775 7450);
FORCEPROP 1 LAST COMMENT_BODY TRUE
J 0
(-14000 7500);
DISPLAY 0.872340 (-14000 7500);
PAINT PEACH (-14000 7500);
DISPLAY INVISIBLE (-14000 7500);
FORCEPROP 2 LAST PATH I95
J 0
(-14050 7650);
DISPLAY 0.680851 (-14050 7650);
DISPLAY INVISIBLE (-14050 7650);
FORCEADD Q_RES..1
(-14925 8125);
FORCEPROP 1 LAST LOCATION R3858
J 0
(-15150 8125);
DISPLAY 0.638298 (-15150 8125);
FORCEPROP 0 LAST $SEC 1
J 0
(-15150 8175);
DISPLAY 0.680851 (-15150 8175);
PAINT MONO (-15150 8175);
DISPLAY INVISIBLE (-15150 8175);
FORCEPROP 0 LAST CDS_SEC 1
J 0
(-15150 8175);
DISPLAY 1.021277 (-15150 8175);
DISPLAY INVISIBLE (-15150 8175);
FORCEPROP 1 LASTPIN (-15025 8125) $PN 1
J 0
(-15013 8137);
DISPLAY 0.787234 (-15013 8137);
PAINT MONO (-15013 8137);
FORCEPROP 1 LASTPIN (-14825 8125) $PN 2
J 0
(-14863 8137);
DISPLAY 0.787234 (-14863 8137);
PAINT MONO (-14863 8137);
FORCEPROP 1 LAST MATERIAL CHIP
J 0
(-14625 8125);
DISPLAY 0.510638 (-14625 8125);
FORCEPROP 1 LAST VALUE 33.2
J 2
(-14725 8125);
DISPLAY 0.510638 (-14725 8125);
FORCEPROP 1 LAST TOLERANCE 1%
J 0
(-14700 8125);
DISPLAY 0.510638 (-14700 8125);
FORCEPROP 2 LAST CDS_LIB pure_quanta
J 0
(-14925 8125);
DISPLAY INVISIBLE (-14925 8125);
FORCEPROP 1 LAST PACK_TYPE 0402LF
J 0
(-15050 8225);
DISPLAY 0.404255 (-15050 8225);
DISPLAY INVISIBLE (-15050 8225);
FORCEPROP 1 LAST WATTAGE 1/16W
J 2
(-14825 8225);
DISPLAY 0.404255 (-14825 8225);
DISPLAY INVISIBLE (-14825 8225);
FORCEPROP 1 LAST PATH I96
J 0
(-14975 8275);
DISPLAY 0.978723 (-14975 8275);
PAINT WHITE (-14975 8275);
DISPLAY INVISIBLE (-14975 8275);
FORCEPROP 1 LAST PART_NUMBER CS03322FB03
J 0
(-15050 8175);
DISPLAY 0.404255 (-15050 8175);
DISPLAY INVISIBLE (-15050 8175);
FORCEADD Q_RES..1
(-14925 8175);
FORCEPROP 1 LAST LOCATION R2425
J 0
(-15150 8175);
DISPLAY 0.638298 (-15150 8175);
FORCEPROP 0 LAST $SEC 1
J 0
(-15150 8225);
DISPLAY 0.680851 (-15150 8225);
PAINT MONO (-15150 8225);
DISPLAY INVISIBLE (-15150 8225);
FORCEPROP 0 LAST CDS_SEC 1
J 0
(-15150 8225);
DISPLAY 1.021277 (-15150 8225);
DISPLAY INVISIBLE (-15150 8225);
FORCEPROP 1 LASTPIN (-15025 8175) $PN 1
J 0
(-15013 8187);
DISPLAY 0.787234 (-15013 8187);
PAINT MONO (-15013 8187);
FORCEPROP 1 LASTPIN (-14825 8175) $PN 2
J 0
(-14863 8187);
DISPLAY 0.787234 (-14863 8187);
PAINT MONO (-14863 8187);
FORCEPROP 1 LAST TOLERANCE 1%
J 0
(-14700 8175);
DISPLAY 0.510638 (-14700 8175);
FORCEPROP 1 LAST MATERIAL CHIP
J 0
(-14625 8175);
DISPLAY 0.510638 (-14625 8175);
FORCEPROP 1 LAST VALUE 33.2
J 2
(-14725 8175);
DISPLAY 0.510638 (-14725 8175);
FORCEPROP 1 LAST WATTAGE 1/16W
J 2
(-14825 8275);
DISPLAY 0.404255 (-14825 8275);
DISPLAY INVISIBLE (-14825 8275);
FORCEPROP 1 LAST PACK_TYPE 0402LF
J 0
(-15050 8275);
DISPLAY 0.404255 (-15050 8275);
DISPLAY INVISIBLE (-15050 8275);
FORCEPROP 2 LAST CDS_LIB pure_quanta
J 0
(-14925 8175);
DISPLAY INVISIBLE (-14925 8175);
FORCEPROP 1 LAST PATH I97
J 0
(-14975 8325);
DISPLAY 0.978723 (-14975 8325);
PAINT WHITE (-14975 8325);
DISPLAY INVISIBLE (-14975 8325);
FORCEPROP 1 LAST PART_NUMBER CS03322FB03
J 0
(-15050 8225);
DISPLAY 0.404255 (-15050 8225);
DISPLAY INVISIBLE (-15050 8225);
FORCEADD Q_RES..1
(-14925 8475);
FORCEPROP 1 LAST LOCATION R2421
J 0
(-15150 8475);
DISPLAY 0.638298 (-15150 8475);
FORCEPROP 0 LAST $SEC 1
J 0
(-15150 8525);
DISPLAY 0.680851 (-15150 8525);
PAINT MONO (-15150 8525);
DISPLAY INVISIBLE (-15150 8525);
FORCEPROP 0 LAST CDS_SEC 1
J 0
(-15150 8525);
DISPLAY 1.021277 (-15150 8525);
DISPLAY INVISIBLE (-15150 8525);
FORCEPROP 1 LASTPIN (-15025 8475) $PN 1
J 0
(-15013 8487);
DISPLAY 0.787234 (-15013 8487);
PAINT MONO (-15013 8487);
FORCEPROP 1 LASTPIN (-14825 8475) $PN 2
J 0
(-14863 8487);
DISPLAY 0.787234 (-14863 8487);
PAINT MONO (-14863 8487);
FORCEPROP 1 LAST TOLERANCE 1%
J 0
(-14700 8475);
DISPLAY 0.510638 (-14700 8475);
FORCEPROP 1 LAST MATERIAL CHIP
J 0
(-14625 8475);
DISPLAY 0.510638 (-14625 8475);
FORCEPROP 1 LAST VALUE 33.2
J 2
(-14725 8475);
DISPLAY 0.510638 (-14725 8475);
FORCEPROP 2 LAST CDS_LIB pure_quanta
J 0
(-14925 8475);
DISPLAY INVISIBLE (-14925 8475);
FORCEPROP 1 LAST PACK_TYPE 0402LF
J 0
(-15050 8575);
DISPLAY 0.404255 (-15050 8575);
DISPLAY INVISIBLE (-15050 8575);
FORCEPROP 1 LAST WATTAGE 1/16W
J 2
(-14825 8575);
DISPLAY 0.404255 (-14825 8575);
DISPLAY INVISIBLE (-14825 8575);
FORCEPROP 1 LAST PATH I98
J 0
(-14975 8625);
DISPLAY 0.978723 (-14975 8625);
PAINT WHITE (-14975 8625);
DISPLAY INVISIBLE (-14975 8625);
FORCEPROP 1 LAST PART_NUMBER CS03322FB03
J 0
(-15050 8525);
DISPLAY 0.404255 (-15050 8525);
DISPLAY INVISIBLE (-15050 8525);
FORCEADD DNS..2
(-9850 9125);
PAINT RED (-9850 9125);
FORCEPROP 2 LAST CDS_LIB mstr_misc
J 0
(-9850 9125);
DISPLAY INVISIBLE (-9850 9125);
FORCEPROP 1 LAST COMMENT_BODY TRUE
J 0
(-9850 9125);
DISPLAY INVISIBLE (-9850 9125);
FORCEADD DESIGN_NOTE..1
(-10800 10100);
FORCEPROP 0 LAST L1 UART_1 MB TO BMC (BMC SLAVE)
J 0
(-11000 9975);
DISPLAY 0.808511 (-11000 9975);
PAINT SKYBLUE (-11000 9975);
FORCEPROP 0 LAST L2 UART_2 BMC TO MB (BMC HOST)
J 0
(-11000 9900);
DISPLAY 0.808511 (-11000 9900);
PAINT SKYBLUE (-11000 9900);
FORCEPROP 2 LAST CDS_LIB pure_quanta_power
J 0
(-10800 10100);
DISPLAY INVISIBLE (-10800 10100);
FORCEPROP 1 LAST COMMENT_BODY TRUE
J 0
(-10775 10200);
DISPLAY 0.978723 (-10775 10200);
DISPLAY INVISIBLE (-10775 10200);
FORCEADD DNS..2
(-15250 4200);
PAINT RED (-15250 4200);
FORCEPROP 2 LAST CDS_LIB mstr_misc
J 0
(-15250 4200);
DISPLAY INVISIBLE (-15250 4200);
FORCEPROP 1 LAST COMMENT_BODY TRUE
J 0
(-15250 4200);
DISPLAY INVISIBLE (-15250 4200);
FORCEADD DNS..2
(-9500 5125);
PAINT RED (-9500 5125);
FORCEPROP 2 LAST CDS_LIB mstr_misc
J 0
(-9500 5125);
DISPLAY INVISIBLE (-9500 5125);
FORCEPROP 1 LAST COMMENT_BODY TRUE
J 0
(-9500 5125);
DISPLAY INVISIBLE (-9500 5125);
FORCEADD DNS..2
(-16850 6325);
PAINT RED (-16850 6325);
FORCEPROP 2 LAST CDS_LIB mstr_misc
J 0
(-16850 6325);
DISPLAY INVISIBLE (-16850 6325);
FORCEPROP 1 LAST COMMENT_BODY TRUE
J 0
(-16850 6325);
DISPLAY INVISIBLE (-16850 6325);
FORCEADD DNS..2
(-9850 9050);
PAINT RED (-9850 9050);
FORCEPROP 2 LAST CDS_LIB mstr_misc
J 0
(-9850 9050);
DISPLAY INVISIBLE (-9850 9050);
FORCEPROP 1 LAST COMMENT_BODY TRUE
J 0
(-9850 9050);
DISPLAY INVISIBLE (-9850 9050);
FORCEADD QUANTA_TITLE_BLOCK_C..1
(-7775 3750);
FORCEPROP 0 LAST CDS_CON_LAST_MODIFIED Thu Sep 14 16:12:32 2023
J 0
(-9660 3765);
DISPLAY INVISIBLE (-9660 3765);
FORCEPROP 2 LAST CUSTOM_TXT_CDS <XR_PAGE_TITLE>
J 0
(-15665 9000);
DISPLAY 0.638298 (-15665 9000);
PAINT PINK (-15665 9000);
DISPLAY INVISIBLE (-15665 9000);
FORCEPROP 2 LAST CUSTOM_TXT_CDS CR-210 : @S9S_MB_LIB.S9S_MB(SCH_1):PAGE210
J 0
(-15665 9000);
DISPLAY 0.638298 (-15665 9000);
PAINT PINK (-15665 9000);
DISPLAY INVISIBLE (-15665 9000);
FORCEPROP 2 LAST CUSTOM_TXT_CDS <CON_LAST_MODIFIED>
J 0
(-9660 3765);
DISPLAY 0.978723 (-9660 3765);
FORCEPROP 2 LAST CUSTOM_TXT_CDS <CON_PAGE_NUM> OF <CON_TOTAL_PAGES>
J 0
(-8250 3775);
DISPLAY 0.978723 (-8250 3775);
FORCEPROP 2 LAST CUSTOM_TXT_CDS <Q_REV>
J 0
(-7959 3853);
DISPLAY 1.212766 (-7959 3853);
FORCEPROP 2 LAST CUSTOM_TXT_CDS <Q_NUMBER>
J 0
(-9178 3853);
DISPLAY 1.212766 (-9178 3853);
FORCEPROP 2 LAST CUSTOM_TXT_CDS <NAME_2>
J 0
(-10950 3800);
FORCEPROP 2 LAST CUSTOM_TXT_CDS <Q_PROJ>
J 0
(-10100 3850);
DISPLAY 1.212766 (-10100 3850);
FORCEPROP 1 LAST CUSTOM_TXT_CDS <NAME_1>
J 0
(-10950 3925);
FORCEPROP 1 LAST Q_TITLE SCM CONN
J 0
(-17141 3776);
DISPLAY 2.446809 (-17141 3776);
PAINT GREEN (-17141 3776);
FORCEPROP 2 LAST PAGE_BORDER TRUE
J 0
(-15665 9000);
DISPLAY 0.638298 (-15665 9000);
PAINT PINK (-15665 9000);
DISPLAY INVISIBLE (-15665 9000);
FORCEPROP 2 LAST CDS_LIB pure_quanta
J 0
(-7775 3750);
DISPLAY INVISIBLE (-7775 3750);
FORCEPROP 1 LAST CDS_LMAN_SYM_OUTLINE -9475,6775,100,-125
J 0
(-7775 3750);
DISPLAY 0.468085 (-7775 3750);
PAINT GREEN (-7775 3750);
DISPLAY INVISIBLE (-7775 3750);
FORCEPROP 2 LAST CDS_XR_PAGE_TITLE CR-150 : @T6G_MB_LIB.T6G(SCH_1):PAGE150
J 0
(-15665 9000);
DISPLAY 0.638298 (-15665 9000);
PAINT PINK (-15665 9000);
DISPLAY INVISIBLE (-15665 9000);
FORCEPROP 1 LAST Q_DEPT BU9
J 1
(-11538 3799);
DISPLAY 1.957447 (-11538 3799);
PAINT GREEN (-11538 3799);
DISPLAY INVISIBLE (-11538 3799);
FORCEPROP 1 LAST COMMENT_BODY TRUE
J 0
(-7763 3737);
DISPLAY 0.978723 (-7763 3737);
PAINT PEACH (-7763 3737);
DISPLAY INVISIBLE (-7763 3737);
WIRE 16 -1 (-15200 4100)(-15200 4000);
WIRE 16 -1 (-9275 9450)(-9275 9400);
WIRE 16 -1 (-8450 8300)(-8450 8375);
WIRE 16 -1 (-16775 6450)(-16775 6550);
WIRE 16 -1 (-15200 4925)(-15200 4800);
WIRE 16 -1 (-16725 5425)(-16725 5275);
WIRE 16 -1 (-8500 6575)(-8500 6525);
WIRE 16 -1 (-14525 8975)(-15575 8975);
FORCEPROP 2 LAST SIG_NAME I3C_SCM_3_R_SCL
J 0
(-15460 8985);
DISPLAY 0.638298 (-15460 8985);
PAINT WHITE (-15460 8985);
WIRE 16 -1 (-15575 9275)(-14525 9275);
FORCEPROP 2 LAST SIG_NAME I3C_SCM_0_R_SCL
J 0
(-15460 9285);
DISPLAY 0.638298 (-15460 9285);
PAINT WHITE (-15460 9285);
WIRE 16 -1 (-15575 9225)(-14525 9225);
FORCEPROP 2 LAST SIG_NAME I3C_SCM_0_R_SDA
J 0
(-15460 9235);
DISPLAY 0.638298 (-15460 9235);
PAINT WHITE (-15460 9235);
WIRE 16 -1 (-15050 6725)(-16175 6725);
FORCEPROP 0 LAST SIG_NAME SMB_1_BMC_GPU_SCL
J 0
(-16060 6735);
DISPLAY 0.553191 (-16060 6735);
PAINT WHITE (-16060 6735);
WIRE 16 -1 (-16775 6025)(-12700 6025);
FORCEPROP 0 LAST CDS_PHYS_NET_NAME TP_JTAG_DBP_BMC_PRDY_N
J 0
(-13735 6065);
PAINT MONO (-13735 6065);
DISPLAY INVISIBLE (-13735 6065);
FORCEPROP 2 LAST SIG_NAME PU_JTAG_DBP_BMC_PRDY_N
J 0
(-15985 6035);
DISPLAY 0.638298 (-15985 6035);
PAINT WHITE (-15985 6035);
FORCEPROP 2 LASTPROP $XRERR UNIQUE?
J 0
(-16225 6035);
DISPLAY 0.638298 (-16225 6035);
PAINT MONO (-16225 6035);
DISPLAY INVISIBLE (-16225 6035);
WIRE 16 -1 (-16775 6025)(-16775 6250);
WIRE 16 -1 (-15050 6225)(-16175 6225);
FORCEPROP 2 LAST SIG_NAME RST_MB_STBY_N
J 0
(-16085 6235);
DISPLAY 0.638298 (-16085 6235);
PAINT WHITE (-16085 6235);
WIRE 16 -1 (-15925 4475)(-15200 4475);
FORCEPROP 2 LAST SIG_NAME SCM_ROT_CPU_RST_R_N
J 0
(-15835 4485);
DISPLAY 0.638298 (-15835 4485);
PAINT WHITE (-15835 4485);
WIRE 16 -1 (-15200 4600)(-15200 4475);
WIRE 16 -1 (-15200 4475)(-15200 4300);
WIRE 16 -1 (-12700 9425)(-12925 9425);
WIRE 16 -1 (-12925 9425)(-12925 9475);
WIRE 16 -1 (-12700 9475)(-12925 9475);
WIRE 16 -1 (-12925 9475)(-12925 9700);
WIRE 16 -1 (-11200 9475)(-11200 9425);
WIRE 16 -1 (-11200 9700)(-11200 9475);
WIRE 16 -1 (-11400 9475)(-11200 9475);
WIRE 16 -1 (-11200 9425)(-11400 9425);
WIRE 16 -1 (-11400 6575)(-8700 6575);
WIRE 16 -1 (-8700 6575)(-8700 6825);
WIRE 16 -1 (-8500 6825)(-8700 6825);
WIRE 16 -1 (-8700 6825)(-8700 6900);
WIRE 16 -1 (-8500 6825)(-8500 6775);
WIRE 16 -1 (-12700 4725)(-12925 4725);
WIRE 16 -1 (-12925 4725)(-12925 4775);
WIRE 16 -1 (-12925 4675)(-12925 4725);
WIRE 16 -1 (-12700 4775)(-12925 4775);
WIRE 16 -1 (-12925 4775)(-12925 4825);
WIRE 16 -1 (-12700 4825)(-12925 4825);
WIRE 16 -1 (-12925 4825)(-12925 4875);
WIRE 16 -1 (-12700 4875)(-12925 4875);
WIRE 16 -1 (-12925 4875)(-12925 4925);
WIRE 16 -1 (-12700 4925)(-12925 4925);
WIRE 16 -1 (-12925 4925)(-12925 5025);
WIRE 16 -1 (-12925 5025)(-12925 5175);
WIRE 16 -1 (-12700 5025)(-12925 5025);
WIRE 16 -1 (-12700 5175)(-12925 5175);
WIRE 16 -1 (-12925 5175)(-12925 5325);
WIRE 16 -1 (-12700 5325)(-12925 5325);
WIRE 16 -1 (-12925 5325)(-12925 5475);
WIRE 16 -1 (-12700 5475)(-12925 5475);
WIRE 16 -1 (-12925 5475)(-12925 5625);
WIRE 16 -1 (-12925 5625)(-12925 6525);
WIRE 16 -1 (-12700 5625)(-12925 5625);
WIRE 16 -1 (-12700 6525)(-12925 6525);
WIRE 16 -1 (-12925 6525)(-12925 6975);
WIRE 16 -1 (-12925 7625)(-12925 6975);
WIRE 16 -1 (-12700 6975)(-12925 6975);
WIRE 16 -1 (-12700 7625)(-12925 7625);
WIRE 16 -1 (-12925 7775)(-12925 7625);
WIRE 16 -1 (-12700 7775)(-12925 7775);
WIRE 16 -1 (-12925 7925)(-12925 7775);
WIRE 16 -1 (-12700 7925)(-12925 7925);
WIRE 16 -1 (-12925 8075)(-12925 7925);
WIRE 16 -1 (-12925 8875)(-12925 8075);
WIRE 16 -1 (-12700 8075)(-12925 8075);
WIRE 16 -1 (-12925 9325)(-12925 8875);
WIRE 16 -1 (-12700 8875)(-12925 8875);
WIRE 16 -1 (-12700 9325)(-12925 9325);
WIRE 16 -1 (-12925 9325)(-12925 9375);
WIRE 16 -1 (-12700 9375)(-12925 9375);
WIRE 16 -1 (-11400 5025)(-11200 5025);
WIRE 16 -1 (-11200 5025)(-11200 5175);
WIRE 16 -1 (-11200 4750)(-11200 5025);
WIRE 16 -1 (-11200 5175)(-11200 5325);
WIRE 16 -1 (-11400 5175)(-11200 5175);
WIRE 16 -1 (-11200 5325)(-11200 5475);
WIRE 16 -1 (-11400 5325)(-11200 5325);
WIRE 16 -1 (-11200 5475)(-11200 5625);
WIRE 16 -1 (-11400 5475)(-11200 5475);
WIRE 16 -1 (-11200 5625)(-11200 5775);
WIRE 16 -1 (-11400 5625)(-11200 5625);
WIRE 16 -1 (-11200 5775)(-11200 5925);
WIRE 16 -1 (-11400 5775)(-11200 5775);
WIRE 16 -1 (-11200 5925)(-11200 6075);
WIRE 16 -1 (-11400 5925)(-11200 5925);
WIRE 16 -1 (-11200 6725)(-11200 6075);
WIRE 16 -1 (-11400 6075)(-11200 6075);
WIRE 16 -1 (-11200 6725)(-11200 6975);
WIRE 16 -1 (-11400 6725)(-11200 6725);
WIRE 16 -1 (-11200 6975)(-11200 7425);
WIRE 16 -1 (-11400 6975)(-11200 6975);
WIRE 16 -1 (-11200 7425)(-11200 7875);
WIRE 16 -1 (-11400 7425)(-11200 7425);
WIRE 16 -1 (-11200 7875)(-11200 8225);
WIRE 16 -1 (-11400 7875)(-11200 7875);
WIRE 16 -1 (-11200 9025)(-11200 8225);
WIRE 16 -1 (-11400 8225)(-11200 8225);
WIRE 16 -1 (-11200 9175)(-11200 9025);
WIRE 16 -1 (-11400 9025)(-11200 9025);
WIRE 16 -1 (-11200 9175)(-11200 9325);
WIRE 16 -1 (-11400 9175)(-11200 9175);
WIRE 16 -1 (-11400 9325)(-11200 9325);
WIRE 16 -1 (-12700 5825)(-16725 5825);
FORCEPROP 2 LAST SIG_NAME TP_CHASI
J 0
(-16085 5835);
DISPLAY 0.638298 (-16085 5835);
PAINT RED (-16085 5835);
FORCEPROP 2 LASTPROP $XRERR UNIQUE?
J 0
(-16990 5825);
DISPLAY 0.638298 (-16990 5825);
PAINT MONO (-16990 5825);
DISPLAY INVISIBLE (-16990 5825);
WIRE 16 -1 (-16725 5625)(-16725 5825);
WIRE 16 -1 (-16175 6125)(-12700 6125);
FORCEPROP 0 LAST CDS_PHYS_NET_NAME SCM_SYS_PWROK_R
J 0
(-15860 6165);
PAINT MONO (-15860 6165);
DISPLAY INVISIBLE (-15860 6165);
FORCEPROP 2 LAST SIG_NAME SCM_SYS_PWROK_R1
J 0
(-13960 6135);
DISPLAY 0.638298 (-13960 6135);
PAINT WHITE (-13960 6135);
WIRE 16 -1 (-15050 6175)(-16175 6175);
FORCEPROP 0 LAST CDS_PHYS_NET_NAME SCM_SYS_PWRBTN_N
J 0
(-15460 6217);
PAINT MONO (-15460 6217);
DISPLAY INVISIBLE (-15460 6217);
FORCEPROP 2 LAST SIG_NAME SCM_SYS_PWRBTN_N
J 0
(-16085 6185);
DISPLAY 0.553191 (-16085 6185);
PAINT WHITE (-16085 6185);
WIRE 16 -1 (-15050 6325)(-16175 6325);
FORCEPROP 0 LAST CDS_PHYS_NET_NAME PWRGD_PS_PWROK
J 0
(-15460 6367);
PAINT MONO (-15460 6367);
DISPLAY INVISIBLE (-15460 6367);
FORCEPROP 2 LAST SIG_NAME PWRGD_PS_PWROK
J 0
(-16085 6335);
DISPLAY 0.638298 (-16085 6335);
PAINT WHITE (-16085 6335);
WIRE 16 -1 (-15050 6575)(-16150 6575);
FORCEPROP 2 LAST SIG_NAME SMB_HOST_CLK_3V3AUX_SDA
J 0
(-16060 6585);
DISPLAY 0.510638 (-16060 6585);
PAINT WHITE (-16060 6585);
WIRE 16 -1 (-12700 7675)(-14050 7675);
FORCEPROP 2 LAST SIG_NAME P2E_CPU0_P5_RX_DN
J 0
(-13960 7685);
DISPLAY 0.638298 (-13960 7685);
PAINT WHITE (-13960 7685);
WIRE 16 -1 (-10050 8425)(-11400 8425);
FORCEPROP 2 LAST SIG_NAME ESPI_CPU0_D1
J 0
(-11085 8435);
DISPLAY 0.638298 (-11085 8435);
PAINT WHITE (-11085 8435);
WIRE 16 -1 (-10050 8475)(-11400 8475);
FORCEPROP 2 LAST SIG_NAME ESPI_CPU0_D0
J 0
(-11085 8485);
DISPLAY 0.638298 (-11085 8485);
PAINT WHITE (-11085 8485);
WIRE 16 -1 (-10050 8625)(-11400 8625);
FORCEPROP 2 LAST SIG_NAME ESPI_CPU0_CS1_N
J 0
(-11085 8635);
DISPLAY 0.638298 (-11085 8635);
PAINT WHITE (-11085 8635);
WIRE 16 -1 (-10050 8675)(-11400 8675);
FORCEPROP 2 LAST SIG_NAME CLK_ESPI_CPU0_CLK1
J 0
(-11085 8685);
DISPLAY 0.638298 (-11085 8685);
PAINT WHITE (-11085 8685);
WIRE 16 -1 (-8450 8675)(-8975 8675);
WIRE 16 -1 (-8450 8575)(-8450 8675);
WIRE 16 -1 (-8975 8675)(-8975 8275);
WIRE 16 -1 (-8975 8275)(-11400 8275);
FORCEPROP 2 LAST SIG_NAME FM_LPC_ESPI_SEL
J 0
(-11085 8285);
DISPLAY 0.638298 (-11085 8285);
PAINT WHITE (-11085 8285);
FORCEPROP 2 LASTPROP $XRERR UNIQUE?
J 0
(-11325 8285);
DISPLAY 0.638298 (-11325 8285);
PAINT MONO (-11325 8285);
DISPLAY INVISIBLE (-11325 8285);
WIRE 16 -1 (-9425 6675)(-10200 6675);
FORCEPROP 2 LAST SIG_NAME SGPIO_SCM_RESET_N
J 0
(-10010 6685);
DISPLAY 0.638298 (-10010 6685);
PAINT WHITE (-10010 6685);
WIRE 16 -1 (-10400 6675)(-11400 6675);
FORCEPROP 0 LAST CDS_PHYS_NET_NAME SGPIO_SCM_RESET_R_N
J 0
(-11310 6715);
PAINT MONO (-11310 6715);
DISPLAY INVISIBLE (-11310 6715);
FORCEPROP 2 LAST SIG_NAME SGPIO_SCM_RESET_R_N
J 0
(-11085 6685);
DISPLAY 0.638298 (-11085 6685);
PAINT WHITE (-11085 6685);
FORCEPROP 2 LASTPROP $XRERR UNIQUE?
J 0
(-11325 6685);
DISPLAY 0.638298 (-11325 6685);
PAINT MONO (-11325 6685);
DISPLAY INVISIBLE (-11325 6685);
WIRE 16 -1 (-10400 6625)(-11400 6625);
FORCEPROP 0 LAST CDS_PHYS_NET_NAME SGPIO_SCM_INTR_R_N
J 0
(-11310 6665);
PAINT MONO (-11310 6665);
DISPLAY INVISIBLE (-11310 6665);
FORCEPROP 2 LAST SIG_NAME SGPIO_SCM_INTR_R1_N
J 0
(-11085 6635);
DISPLAY 0.638298 (-11085 6635);
PAINT WHITE (-11085 6635);
FORCEPROP 2 LASTPROP $XRERR UNIQUE?
J 0
(-11325 6635);
DISPLAY 0.638298 (-11325 6635);
PAINT MONO (-11325 6635);
DISPLAY INVISIBLE (-11325 6635);
WIRE 16 -1 (-10050 6375)(-11400 6375);
FORCEPROP 0 LAST CDS_PHYS_NET_NAME TP_SPI_2_PLD_CLK
J 0
(-11310 6409);
PAINT MONO (-11310 6409);
DISPLAY INVISIBLE (-11310 6409);
FORCEPROP 2 LAST SIG_NAME TP_SPI_2_PLD_CLK
J 0
(-11085 6385);
DISPLAY 0.638298 (-11085 6385);
PAINT WHITE (-11085 6385);
FORCEPROP 2 LASTPROP $XRERR UNIQUE?
J 0
(-10020 6375);
DISPLAY 0.638298 (-10020 6375);
PAINT MONO (-10020 6375);
DISPLAY INVISIBLE (-10020 6375);
WIRE 16 -1 (-10050 6325)(-11400 6325);
FORCEPROP 0 LAST CDS_PHYS_NET_NAME TP_SPI_2_PLD_CS_N
J 0
(-11310 6359);
PAINT MONO (-11310 6359);
DISPLAY INVISIBLE (-11310 6359);
FORCEPROP 2 LAST SIG_NAME TP_SPI_2_PLD_CS_N
J 0
(-11085 6335);
DISPLAY 0.638298 (-11085 6335);
PAINT WHITE (-11085 6335);
FORCEPROP 2 LASTPROP $XRERR UNIQUE?
J 0
(-10020 6325);
DISPLAY 0.638298 (-10020 6325);
PAINT MONO (-10020 6325);
DISPLAY INVISIBLE (-10020 6325);
WIRE 16 -1 (-14050 5525)(-12700 5525);
FORCEPROP 2 LAST SIG_NAME USB3_CPU0_BMC_RX_DN
J 0
(-13960 5535);
DISPLAY 0.680851 (-13960 5535);
PAINT WHITE (-13960 5535);
WIRE 16 -1 (-12700 5075)(-14050 5075);
FORCEPROP 2 LAST SIG_NAME CLK_100M_BMC_RC_DN
J 0
(-13960 5085);
DISPLAY 0.638298 (-13960 5085);
PAINT RED (-13960 5085);
WIRE 16 -1 (-15075 5725)(-16175 5725);
FORCEPROP 2 LAST SIG_NAME SCM_IRQ_N
J 0
(-16085 5735);
DISPLAY 0.638298 (-16085 5735);
PAINT WHITE (-16085 5735);
WIRE 16 -1 (-16175 5775)(-15075 5775);
FORCEPROP 2 LAST SIG_NAME FM_UARTSW_LSB_N
J 0
(-16085 5785);
DISPLAY 0.680851 (-16085 5785);
PAINT WHITE (-16085 5785);
WIRE 16 -1 (-15075 5875)(-16175 5875);
FORCEPROP 2 LAST SIG_NAME SCM_ROT_CPU_RST_R_N
J 0
(-16085 5885);
DISPLAY 0.638298 (-16085 5885);
PAINT WHITE (-16085 5885);
WIRE 16 -1 (-14050 5575)(-12700 5575);
FORCEPROP 2 LAST SIG_NAME USB3_CPU0_BMC_RX_DP
J 0
(-13960 5585);
DISPLAY 0.680851 (-13960 5585);
PAINT WHITE (-13960 5585);
WIRE 16 -1 (-12700 5675)(-14050 5675);
FORCEPROP 2 LAST SIG_NAME FM_SCM_PRSNT1_N
J 0
(-13960 5685);
DISPLAY 0.638298 (-13960 5685);
PAINT WHITE (-13960 5685);
WIRE 16 -1 (-12700 7075)(-14850 7075);
FORCEPROP 0 LAST SIG_NAME SMB_PCIE2_3V3AUX_SCL_R0
J 0
(-13960 7085);
DISPLAY 0.680851 (-13960 7085);
PAINT WHITE (-13960 7085);
FORCEPROP 2 LASTPROP $XRERR UNIQUE?
J 0
(-14200 7085);
DISPLAY 0.638298 (-14200 7085);
PAINT MONO (-14200 7085);
DISPLAY INVISIBLE (-14200 7085);
WIRE 16 -1 (-12700 7025)(-14850 7025);
FORCEPROP 0 LAST SIG_NAME SMB_PCIE2_3V3AUX_SDA_R0
J 0
(-13960 7035);
DISPLAY 0.680851 (-13960 7035);
PAINT WHITE (-13960 7035);
FORCEPROP 2 LASTPROP $XRERR UNIQUE?
J 0
(-14200 7035);
DISPLAY 0.638298 (-14200 7035);
PAINT MONO (-14200 7035);
DISPLAY INVISIBLE (-14200 7035);
WIRE 16 -1 (-12700 6225)(-14850 6225);
FORCEPROP 0 LAST CDS_PHYS_NET_NAME RST_MB_STBY_R_N
J 0
(-16060 6259);
PAINT MONO (-16060 6259);
DISPLAY INVISIBLE (-16060 6259);
FORCEPROP 2 LAST SIG_NAME RST_MB_STBY_R_N
J 0
(-13960 6235);
DISPLAY 0.638298 (-13960 6235);
PAINT WHITE (-13960 6235);
FORCEPROP 2 LASTPROP $XRERR UNIQUE?
J 0
(-14200 6235);
DISPLAY 0.638298 (-14200 6235);
PAINT MONO (-14200 6235);
DISPLAY INVISIBLE (-14200 6235);
WIRE 16 -1 (-14850 6075)(-12700 6075);
FORCEPROP 0 LAST CDS_PHYS_NET_NAME SCM_HDT_DBREQ_N
J 0
(-15860 6115);
PAINT MONO (-15860 6115);
DISPLAY INVISIBLE (-15860 6115);
FORCEPROP 2 LAST SIG_NAME SCM_HDT_DBREQ_N
J 0
(-13960 6085);
DISPLAY 0.638298 (-13960 6085);
PAINT WHITE (-13960 6085);
FORCEPROP 2 LASTPROP $XRERR UNIQUE?
J 0
(-14200 6085);
DISPLAY 0.638298 (-14200 6085);
PAINT MONO (-14200 6085);
DISPLAY INVISIBLE (-14200 6085);
WIRE 16 -1 (-14875 5925)(-12700 5925);
FORCEPROP 2 LAST SIG_NAME FM_UARTSW_MSB_R
J 0
(-13960 5935);
DISPLAY 0.680851 (-13960 5935);
PAINT RED (-13960 5935);
FORCEPROP 2 LASTPROP $XRERR UNIQUE?
J 0
(-14200 5935);
DISPLAY 0.638298 (-14200 5935);
PAINT MONO (-14200 5935);
DISPLAY INVISIBLE (-14200 5935);
WIRE 16 -1 (-14875 5725)(-12700 5725);
FORCEPROP 2 LAST SIG_NAME IRQ0_A56
J 0
(-13960 5735);
DISPLAY 0.638298 (-13960 5735);
PAINT WHITE (-13960 5735);
FORCEPROP 2 LASTPROP $XRERR UNIQUE?
J 0
(-14200 5735);
DISPLAY 0.638298 (-14200 5735);
PAINT MONO (-14200 5735);
DISPLAY INVISIBLE (-14200 5735);
WIRE 16 -1 (-14875 5775)(-12700 5775);
FORCEPROP 2 LAST SIG_NAME FM_UARTSW_LSB_R
J 0
(-13960 5785);
DISPLAY 0.680851 (-13960 5785);
PAINT RED (-13960 5785);
FORCEPROP 2 LASTPROP $XRERR UNIQUE?
J 0
(-14200 5785);
DISPLAY 0.638298 (-14200 5785);
PAINT MONO (-14200 5785);
DISPLAY INVISIBLE (-14200 5785);
WIRE 16 -1 (-12700 5875)(-14875 5875);
FORCEPROP 2 LAST SIG_NAME SCM_ROT_CPU_RST_N
J 0
(-13960 5885);
DISPLAY 0.638298 (-13960 5885);
PAINT WHITE (-13960 5885);
FORCEPROP 2 LASTPROP $XRERR UNIQUE?
J 0
(-14200 5885);
DISPLAY 0.638298 (-14200 5885);
PAINT MONO (-14200 5885);
DISPLAY INVISIBLE (-14200 5885);
WIRE 16 -1 (-12700 5975)(-14050 5975);
FORCEPROP 2 LAST SIG_NAME FM_RST_PERST_SCM_N
J 0
(-13960 5985);
DISPLAY 0.638298 (-13960 5985);
PAINT WHITE (-13960 5985);
WIRE 16 -1 (-12700 6175)(-14850 6175);
FORCEPROP 0 LAST CDS_PHYS_NET_NAME SCM_SYS_PWRBTN_R_N
J 0
(-14035 6209);
PAINT MONO (-14035 6209);
DISPLAY INVISIBLE (-14035 6209);
FORCEPROP 2 LAST SIG_NAME SCM_SYS_PWRBTN_R_N
J 0
(-13960 6185);
DISPLAY 0.638298 (-13960 6185);
PAINT WHITE (-13960 6185);
FORCEPROP 2 LASTPROP $XRERR UNIQUE?
J 0
(-14200 6185);
DISPLAY 0.638298 (-14200 6185);
PAINT MONO (-14200 6185);
DISPLAY INVISIBLE (-14200 6185);
WIRE 16 -1 (-14625 6275)(-12700 6275);
FORCEPROP 0 LAST CDS_PHYS_NET_NAME TP_STBY_EN
J 0
(-13960 6309);
PAINT MONO (-13960 6309);
DISPLAY INVISIBLE (-13960 6309);
FORCEPROP 2 LAST SIG_NAME TP_STBY_EN
J 0
(-13960 6285);
DISPLAY 0.638298 (-13960 6285);
PAINT RED (-13960 6285);
FORCEPROP 2 LASTPROP $XRERR UNIQUE?
J 0
(-14865 6275);
DISPLAY 0.638298 (-14865 6275);
PAINT MONO (-14865 6275);
DISPLAY INVISIBLE (-14865 6275);
WIRE 16 -1 (-12700 6675)(-14850 6675);
FORCEPROP 0 LAST SIG_NAME SMB_PCIE3_3V3AUX_SDA_R
J 0
(-13960 6685);
DISPLAY 0.680851 (-13960 6685);
PAINT WHITE (-13960 6685);
FORCEPROP 2 LASTPROP $XRERR UNIQUE?
J 0
(-14200 6685);
DISPLAY 0.638298 (-14200 6685);
PAINT MONO (-14200 6685);
DISPLAY INVISIBLE (-14200 6685);
WIRE 16 -1 (-12700 5425)(-14050 5425);
FORCEPROP 2 LAST SIG_NAME TP_PCIE_RXP[1]
J 0
(-13960 5435);
DISPLAY 0.638298 (-13960 5435);
PAINT RED (-13960 5435);
FORCEPROP 2 LASTPROP $XRERR UNIQUE?
J 0
(-14290 5425);
DISPLAY 0.638298 (-14290 5425);
PAINT MONO (-14290 5425);
DISPLAY INVISIBLE (-14290 5425);
WIRE 16 -1 (-12700 5375)(-14050 5375);
FORCEPROP 2 LAST SIG_NAME TP_PCIE_RXN[1]
J 0
(-13960 5385);
DISPLAY 0.638298 (-13960 5385);
PAINT RED (-13960 5385);
FORCEPROP 2 LASTPROP $XRERR UNIQUE?
J 0
(-14290 5375);
DISPLAY 0.638298 (-14290 5375);
PAINT MONO (-14290 5375);
DISPLAY INVISIBLE (-14290 5375);
WIRE 16 -1 (-12700 6325)(-14850 6325);
FORCEPROP 0 LAST CDS_PHYS_NET_NAME PWRGD_PS_PWROK_R
J 0
(-13660 6365);
PAINT MONO (-13660 6365);
DISPLAY INVISIBLE (-13660 6365);
FORCEPROP 2 LAST SIG_NAME PWRGD_PS_PWROK_R
J 0
(-13960 6335);
DISPLAY 0.638298 (-13960 6335);
PAINT WHITE (-13960 6335);
FORCEPROP 2 LASTPROP $XRERR UNIQUE?
J 0
(-14200 6335);
DISPLAY 0.638298 (-14200 6335);
PAINT MONO (-14200 6335);
DISPLAY INVISIBLE (-14200 6335);
WIRE 16 -1 (-12700 6575)(-14850 6575);
FORCEPROP 2 LAST SIG_NAME SMB_HOST_CLK_3V3AUX_SDA_R0
J 0
(-13960 6585);
DISPLAY 0.638298 (-13960 6585);
PAINT WHITE (-13960 6585);
FORCEPROP 2 LASTPROP $XRERR UNIQUE?
J 0
(-14200 6585);
DISPLAY 0.638298 (-14200 6585);
PAINT MONO (-14200 6585);
DISPLAY INVISIBLE (-14200 6585);
WIRE 16 -1 (-12700 6625)(-14850 6625);
FORCEPROP 2 LAST SIG_NAME SMB_HOST_CLK_3V3AUX_SCL_R0
J 0
(-13960 6635);
DISPLAY 0.638298 (-13960 6635);
PAINT WHITE (-13960 6635);
FORCEPROP 2 LASTPROP $XRERR UNIQUE?
J 0
(-14200 6635);
DISPLAY 0.638298 (-14200 6635);
PAINT MONO (-14200 6635);
DISPLAY INVISIBLE (-14200 6635);
WIRE 16 -1 (-16175 5925)(-15075 5925);
FORCEPROP 2 LAST SIG_NAME FM_UARTSW_MSB_N
J 0
(-16085 5935);
DISPLAY 0.680851 (-16085 5935);
PAINT WHITE (-16085 5935);
WIRE 16 -1 (-14850 6375)(-12700 6375);
FORCEPROP 2 LAST SIG_NAME FW_RECOVERY
J 0
(-13960 6385);
DISPLAY 0.638298 (-13960 6385);
PAINT WHITE (-13960 6385);
FORCEPROP 2 LASTPROP $XRERR UNIQUE?
J 0
(-14200 6385);
DISPLAY 0.638298 (-14200 6385);
PAINT MONO (-14200 6385);
DISPLAY INVISIBLE (-14200 6385);
WIRE 16 -1 (-16175 6075)(-15050 6075);
FORCEPROP 2 LAST SIG_NAME JTAG_SCM_DBREQ_N
J 0
(-16085 6085);
DISPLAY 0.638298 (-16085 6085);
PAINT WHITE (-16085 6085);
WIRE 16 -1 (-10200 7025)(-9425 7025);
FORCEPROP 2 LAST SIG_NAME SGPIO_SCM_LD_<0>
J 0
(-10010 7035);
DISPLAY 0.638298 (-10010 7035);
PAINT WHITE (-10010 7035);
WIRE 16 -1 (-9425 6625)(-10200 6625);
FORCEPROP 2 LAST SIG_NAME SGPIO_SCM_INTR_N
J 0
(-10010 6635);
DISPLAY 0.638298 (-10010 6635);
PAINT WHITE (-10010 6635);
WIRE 16 -1 (-10200 7075)(-9425 7075);
FORCEPROP 2 LAST SIG_NAME SGPIO_SCM_DI_<0>
J 0
(-10010 7085);
DISPLAY 0.638298 (-10010 7085);
PAINT WHITE (-10010 7085);
WIRE 16 -1 (-15050 6375)(-16175 6375);
FORCEPROP 2 LAST SIG_NAME FW_RECOVERY_R
J 0
(-16085 6385);
DISPLAY 0.638298 (-16085 6385);
PAINT WHITE (-16085 6385);
WIRE 16 -1 (-15050 6625)(-16175 6625);
FORCEPROP 2 LAST SIG_NAME SMB_HOST_CLK_3V3AUX_SCL
J 0
(-16060 6635);
DISPLAY 0.510638 (-16060 6635);
PAINT WHITE (-16060 6635);
WIRE 16 -1 (-10050 8575)(-11400 8575);
FORCEPROP 2 LAST SIG_NAME ESPI_CPU0_ALERT_N
J 0
(-11085 8585);
DISPLAY 0.638298 (-11085 8585);
PAINT WHITE (-11085 8585);
WIRE 16 -1 (-10050 8525)(-11400 8525);
FORCEPROP 2 LAST SIG_NAME RST_ESPI_CPU0_RSTOUT_N
J 0
(-11085 8535);
DISPLAY 0.638298 (-11085 8535);
PAINT WHITE (-11085 8535);
WIRE 16 -1 (-10050 8375)(-11400 8375);
FORCEPROP 2 LAST SIG_NAME ESPI_CPU0_D2
J 0
(-11085 8385);
DISPLAY 0.638298 (-11085 8385);
PAINT WHITE (-11085 8385);
WIRE 16 -1 (-10050 8325)(-11400 8325);
FORCEPROP 2 LAST SIG_NAME ESPI_CPU0_D3
J 0
(-11085 8335);
DISPLAY 0.638298 (-11085 8335);
PAINT WHITE (-11085 8335);
WIRE 16 -1 (-11400 8175)(-10050 8175);
FORCEPROP 2 LAST SIG_NAME SPI_CPU0_LVC3_SCM_CLK
J 0
(-11085 8185);
DISPLAY 0.638298 (-11085 8185);
PAINT WHITE (-11085 8185);
WIRE 16 -1 (-10050 6275)(-11400 6275);
FORCEPROP 0 LAST CDS_PHYS_NET_NAME TP_SPI_2_PLD_IO0
J 0
(-11310 6309);
PAINT MONO (-11310 6309);
DISPLAY INVISIBLE (-11310 6309);
FORCEPROP 2 LAST SIG_NAME TP_SPI_2_PLD_IO0
J 0
(-11085 6285);
DISPLAY 0.638298 (-11085 6285);
PAINT WHITE (-11085 6285);
FORCEPROP 2 LASTPROP $XRERR UNIQUE?
J 0
(-10020 6275);
DISPLAY 0.638298 (-10020 6275);
PAINT MONO (-10020 6275);
DISPLAY INVISIBLE (-10020 6275);
WIRE 16 -1 (-10400 6525)(-11400 6525);
FORCEPROP 0 LAST CDS_PHYS_NET_NAME TP_QSPI0_CS1_N
J 0
(-11310 6559);
PAINT MONO (-11310 6559);
DISPLAY INVISIBLE (-11310 6559);
FORCEPROP 2 LAST SIG_NAME FM_AC_PWR_BTN_N
J 0
(-11085 6535);
DISPLAY 0.638298 (-11085 6535);
PAINT RED (-11085 6535);
FORCEPROP 2 LASTPROP $XRERR UNIQUE?
J 0
(-11325 6535);
DISPLAY 0.638298 (-11325 6535);
PAINT MONO (-11325 6535);
DISPLAY INVISIBLE (-11325 6535);
WIRE 16 -1 (-10400 6925)(-11400 6925);
FORCEPROP 0 LAST CDS_PHYS_NET_NAME SGPIO_SCM_DO_R_<1>
J 0
(-11310 6959);
PAINT MONO (-11310 6959);
DISPLAY INVISIBLE (-11310 6959);
FORCEPROP 2 LAST SIG_NAME SGPIO_SCM_DO_R_<1>
J 0
(-11085 6935);
DISPLAY 0.638298 (-11085 6935);
PAINT WHITE (-11085 6935);
FORCEPROP 2 LASTPROP $XRERR UNIQUE?
J 0
(-11325 6935);
DISPLAY 0.638298 (-11325 6935);
PAINT MONO (-11325 6935);
DISPLAY INVISIBLE (-11325 6935);
WIRE 16 -1 (-10050 6175)(-11400 6175);
FORCEPROP 0 LAST CDS_PHYS_NET_NAME TP_SPI_2_PLD_IO2
J 0
(-11310 6209);
PAINT MONO (-11310 6209);
DISPLAY INVISIBLE (-11310 6209);
FORCEPROP 2 LAST SIG_NAME TP_SPI_2_PLD_IO2
J 0
(-11085 6185);
DISPLAY 0.638298 (-11085 6185);
PAINT WHITE (-11085 6185);
FORCEPROP 2 LASTPROP $XRERR UNIQUE?
J 0
(-10020 6175);
DISPLAY 0.638298 (-10020 6175);
PAINT MONO (-10020 6175);
DISPLAY INVISIBLE (-10020 6175);
WIRE 16 -1 (-10050 6025)(-11400 6025);
FORCEPROP 2 LAST SIG_NAME USB2_HOST_BMC_B_DP
J 0
(-11085 6035);
DISPLAY 0.638298 (-11085 6035);
PAINT WHITE (-11085 6035);
WIRE 16 -1 (-10050 5975)(-11400 5975);
FORCEPROP 2 LAST SIG_NAME USB2_HOST_BMC_B_DN
J 0
(-11085 5985);
DISPLAY 0.638298 (-11085 5985);
PAINT WHITE (-11085 5985);
WIRE 16 -1 (-10050 5875)(-11400 5875);
FORCEPROP 2 LAST SIG_NAME USB2_CPU0_P1_DP
J 0
(-11085 5885);
DISPLAY 0.638298 (-11085 5885);
PAINT WHITE (-11085 5885);
WIRE 16 -1 (-10050 5825)(-11400 5825);
FORCEPROP 2 LAST SIG_NAME USB2_CPU0_P1_DN
J 0
(-11085 5835);
DISPLAY 0.638298 (-11085 5835);
PAINT WHITE (-11085 5835);
WIRE 16 -1 (-10050 6125)(-11400 6125);
FORCEPROP 0 LAST CDS_PHYS_NET_NAME TP_SPI_2_PLD_IO3
J 0
(-11310 6159);
PAINT MONO (-11310 6159);
DISPLAY INVISIBLE (-11310 6159);
FORCEPROP 2 LAST SIG_NAME TP_SPI_2_PLD_IO3
J 0
(-11085 6135);
DISPLAY 0.638298 (-11085 6135);
PAINT WHITE (-11085 6135);
FORCEPROP 2 LASTPROP $XRERR UNIQUE?
J 0
(-10020 6125);
DISPLAY 0.638298 (-10020 6125);
PAINT MONO (-10020 6125);
DISPLAY INVISIBLE (-10020 6125);
WIRE 16 -1 (-10050 6225)(-11400 6225);
FORCEPROP 0 LAST CDS_PHYS_NET_NAME TP_SPI_2_PLD_IO1
J 0
(-11310 6259);
PAINT MONO (-11310 6259);
DISPLAY INVISIBLE (-11310 6259);
FORCEPROP 2 LAST SIG_NAME TP_SPI_2_PLD_IO1
J 0
(-11085 6235);
DISPLAY 0.638298 (-11085 6235);
PAINT WHITE (-11085 6235);
FORCEPROP 2 LASTPROP $XRERR UNIQUE?
J 0
(-10020 6225);
DISPLAY 0.638298 (-10020 6225);
PAINT MONO (-10020 6225);
DISPLAY INVISIBLE (-10020 6225);
WIRE 16 -1 (-10400 6875)(-11400 6875);
FORCEPROP 2 LAST SIG_NAME SGPIO_SCM_CLK_R_<1>
J 0
(-11085 6885);
DISPLAY 0.638298 (-11085 6885);
PAINT WHITE (-11085 6885);
FORCEPROP 2 LASTPROP $XRERR UNIQUE?
J 0
(-11325 6885);
DISPLAY 0.638298 (-11325 6885);
PAINT MONO (-11325 6885);
DISPLAY INVISIBLE (-11325 6885);
WIRE 16 -1 (-11400 7025)(-10400 7025);
FORCEPROP 2 LAST SIG_NAME SGPIO_SCM_LD_R_<0>
J 0
(-11085 7035);
DISPLAY 0.638298 (-11085 7035);
PAINT WHITE (-11085 7035);
FORCEPROP 2 LASTPROP $XRERR UNIQUE?
J 0
(-11325 7035);
DISPLAY 0.638298 (-11325 7035);
PAINT MONO (-11325 7035);
DISPLAY INVISIBLE (-11325 7035);
WIRE 16 -1 (-11400 7125)(-10400 7125);
FORCEPROP 2 LAST SIG_NAME SGPIO_SCM_CLK_R_<0>
J 0
(-11085 7135);
DISPLAY 0.638298 (-11085 7135);
PAINT WHITE (-11085 7135);
FORCEPROP 2 LASTPROP $XRERR UNIQUE?
J 0
(-11325 7135);
DISPLAY 0.638298 (-11325 7135);
PAINT MONO (-11325 7135);
DISPLAY INVISIBLE (-11325 7135);
WIRE 16 -1 (-11400 6775)(-10400 6775);
FORCEPROP 2 LAST SIG_NAME SGPIO_SCM_LD_R_<1>
J 0
(-11085 6785);
DISPLAY 0.638298 (-11085 6785);
PAINT WHITE (-11085 6785);
FORCEPROP 2 LASTPROP $XRERR UNIQUE?
J 0
(-11325 6785);
DISPLAY 0.638298 (-11325 6785);
PAINT MONO (-11325 6785);
DISPLAY INVISIBLE (-11325 6785);
WIRE 16 -1 (-11400 6825)(-10400 6825);
FORCEPROP 2 LAST SIG_NAME SGPIO_SCM_DI_R_<1>
J 0
(-11085 6835);
DISPLAY 0.638298 (-11085 6835);
PAINT WHITE (-11085 6835);
FORCEPROP 2 LASTPROP $XRERR UNIQUE?
J 0
(-11325 6835);
DISPLAY 0.638298 (-11325 6835);
PAINT MONO (-11325 6835);
DISPLAY INVISIBLE (-11325 6835);
WIRE 16 -1 (-11400 7175)(-10400 7175);
FORCEPROP 2 LAST SIG_NAME SGPIO_SCM_DO_R_<0>
J 0
(-11085 7185);
DISPLAY 0.638298 (-11085 7185);
PAINT WHITE (-11085 7185);
FORCEPROP 2 LASTPROP $XRERR UNIQUE?
J 0
(-11325 7185);
DISPLAY 0.638298 (-11325 7185);
PAINT MONO (-11325 7185);
DISPLAY INVISIBLE (-11325 7185);
WIRE 16 -1 (-11400 8025)(-10050 8025);
FORCEPROP 2 LAST SIG_NAME SPI_CPU0_LVC3_SCM_D1
J 0
(-11085 8035);
DISPLAY 0.638298 (-11085 8035);
PAINT WHITE (-11085 8035);
WIRE 16 -1 (-11400 8075)(-10050 8075);
FORCEPROP 2 LAST SIG_NAME SPI_CPU0_LVC3_SCM_D0
J 0
(-11085 8085);
DISPLAY 0.638298 (-11085 8085);
PAINT WHITE (-11085 8085);
WIRE 16 -1 (-9550 8825)(-11400 8825);
FORCEPROP 2 LAST SIG_NAME FM_SOL_UART_CH_SEL_R
J 0
(-11085 8835);
DISPLAY 0.638298 (-11085 8835);
PAINT RED (-11085 8835);
FORCEPROP 2 LASTPROP $XRERR UNIQUE?
J 0
(-11325 8835);
DISPLAY 0.638298 (-11325 8835);
PAINT MONO (-11325 8835);
DISPLAY INVISIBLE (-11325 8835);
WIRE 16 -1 (-10050 7525)(-11400 7525);
FORCEPROP 2 LAST SIG_NAME RMII_OCP_BMC_RXD_0
J 0
(-11085 7535);
DISPLAY 0.638298 (-11085 7535);
PAINT WHITE (-11085 7535);
WIRE 16 -1 (-10050 5675)(-11400 5675);
FORCEPROP 2 LAST SIG_NAME USB2_HUB_EXT_DN
J 0
(-11085 5685);
DISPLAY 0.638298 (-11085 5685);
PAINT WHITE (-11085 5685);
WIRE 16 -1 (-10050 5725)(-11400 5725);
FORCEPROP 2 LAST SIG_NAME USB2_HUB_EXT_DP
J 0
(-11085 5735);
DISPLAY 0.638298 (-11085 5735);
PAINT WHITE (-11085 5735);
WIRE 16 -1 (-11400 5575)(-10050 5575);
FORCEPROP 2 LAST SIG_NAME USB3_CPU0_BMC_TX_BUF_C_DP
J 0
(-11085 5585);
DISPLAY 0.553191 (-11085 5585);
PAINT WHITE (-11085 5585);
WIRE 16 -1 (-11400 5525)(-10050 5525);
FORCEPROP 2 LAST SIG_NAME USB3_CPU0_BMC_TX_BUF_C_DN
J 0
(-11085 5535);
DISPLAY 0.553191 (-11085 5535);
PAINT WHITE (-11085 5535);
WIRE 16 -1 (-10050 7325)(-11400 7325);
FORCEPROP 2 LAST SIG_NAME TP_PVCCIO_PECI_BMC
J 0
(-11085 7335);
DISPLAY 0.638298 (-11085 7335);
PAINT WHITE (-11085 7335);
FORCEPROP 2 LASTPROP $XRERR UNIQUE?
J 0
(-10020 7325);
DISPLAY 0.638298 (-10020 7325);
PAINT MONO (-10020 7325);
DISPLAY INVISIBLE (-10020 7325);
WIRE 16 -1 (-10050 7375)(-11400 7375);
FORCEPROP 2 LAST SIG_NAME TP_PECI_BMC
J 0
(-11085 7385);
DISPLAY 0.638298 (-11085 7385);
PAINT WHITE (-11085 7385);
FORCEPROP 2 LASTPROP $XRERR UNIQUE?
J 0
(-10020 7375);
DISPLAY 0.638298 (-10020 7375);
PAINT MONO (-10020 7375);
DISPLAY INVISIBLE (-10020 7375);
WIRE 16 -1 (-10050 7475)(-11400 7475);
FORCEPROP 2 LAST SIG_NAME RMII_OCP_BMC_RXD_1
J 0
(-11085 7485);
DISPLAY 0.638298 (-11085 7485);
PAINT WHITE (-11085 7485);
WIRE 16 -1 (-11400 7925)(-10050 7925);
FORCEPROP 2 LAST SIG_NAME SPI_CPU0_LVC3_SCM_D3
J 0
(-11085 7935);
DISPLAY 0.638298 (-11085 7935);
PAINT WHITE (-11085 7935);
WIRE 16 -1 (-11400 7975)(-10050 7975);
FORCEPROP 2 LAST SIG_NAME SPI_CPU0_LVC3_SCM_D2
J 0
(-11085 7985);
DISPLAY 0.638298 (-11085 7985);
PAINT WHITE (-11085 7985);
WIRE 16 -1 (-10050 8125)(-11400 8125);
FORCEPROP 2 LAST SIG_NAME SPI_CPU0_LVC3_SCM_CS0_N
J 0
(-11085 8135);
DISPLAY 0.638298 (-11085 8135);
PAINT WHITE (-11085 8135);
WIRE 16 -1 (-11400 7075)(-10400 7075);
FORCEPROP 2 LAST SIG_NAME SGPIO_SCM_DI_R_<0>
J 0
(-11085 7085);
DISPLAY 0.638298 (-11085 7085);
PAINT WHITE (-11085 7085);
FORCEPROP 2 LASTPROP $XRERR UNIQUE?
J 0
(-11325 7085);
DISPLAY 0.638298 (-11325 7085);
PAINT MONO (-11325 7085);
DISPLAY INVISIBLE (-11325 7085);
WIRE 16 -1 (-10050 7625)(-11400 7625);
FORCEPROP 2 LAST SIG_NAME RMII_BMC_OCP_TXD_1
J 0
(-11085 7635);
DISPLAY 0.638298 (-11085 7635);
PAINT WHITE (-11085 7635);
WIRE 16 -1 (-10050 7725)(-11400 7725);
FORCEPROP 0 LAST CDS_PHYS_NET_NAME RMII_BMC_OCP_TX_EN
J 0
(-11310 7765);
PAINT MONO (-11310 7765);
DISPLAY INVISIBLE (-11310 7765);
FORCEPROP 2 LAST SIG_NAME RMII_BMC_OCP_TX_EN
J 0
(-11085 7735);
DISPLAY 0.638298 (-11085 7735);
PAINT WHITE (-11085 7735);
WIRE 16 -1 (-11400 8875)(-10050 8875);
FORCEPROP 0 LAST CDS_PHYS_NET_NAME TP_H_CPU_CATERR_LVC2_BMC_N
J 0
(-11375 8917);
PAINT MONO (-11375 8917);
DISPLAY INVISIBLE (-11375 8917);
FORCEPROP 0 LAST SIG_NAME FPGA_IO3V3_RSVD_1
J 0
(-11085 8885);
DISPLAY 0.680851 (-11085 8885);
PAINT RED (-11085 8885);
WIRE 16 -1 (-15050 6675)(-16150 6675);
FORCEPROP 0 LAST SIG_NAME SMB_1_BMC_GPU_SDA
J 0
(-16060 6685);
DISPLAY 0.553191 (-16060 6685);
PAINT WHITE (-16060 6685);
WIRE 16 -1 (-12700 5225)(-14050 5225);
FORCEPROP 2 LAST SIG_NAME P2E_MB_BMC_RX_BUF_DN<0>
J 0
(-13960 5235);
DISPLAY 0.638298 (-13960 5235);
PAINT RED (-13960 5235);
WIRE 16 -1 (-12700 5125)(-14050 5125);
FORCEPROP 2 LAST SIG_NAME CLK_100M_BMC_RC_DP
J 0
(-13960 5135);
DISPLAY 0.638298 (-13960 5135);
PAINT RED (-13960 5135);
WIRE 16 -1 (-12700 5275)(-14050 5275);
FORCEPROP 2 LAST SIG_NAME P2E_MB_BMC_RX_BUF_DP<0>
J 0
(-13960 5285);
DISPLAY 0.638298 (-13960 5285);
PAINT RED (-13960 5285);
WIRE 16 -1 (-12700 8125)(-14825 8125);
FORCEPROP 2 LAST SIG_NAME SMB_OCP_V3_2_3V3AUX_SDA_R0
J 0
(-13960 8135);
DISPLAY 0.638298 (-13960 8135);
PAINT WHITE (-13960 8135);
FORCEPROP 2 LASTPROP $XRERR UNIQUE?
J 0
(-14200 8135);
DISPLAY 0.638298 (-14200 8135);
PAINT MONO (-14200 8135);
DISPLAY INVISIBLE (-14200 8135);
WIRE 16 -1 (-12700 8175)(-14825 8175);
FORCEPROP 2 LAST SIG_NAME SMB_OCP_V3_2_3V3AUX_SCL_R0
J 0
(-13960 8185);
DISPLAY 0.638298 (-13960 8185);
PAINT WHITE (-13960 8185);
FORCEPROP 2 LASTPROP $XRERR UNIQUE?
J 0
(-14200 8185);
DISPLAY 0.638298 (-14200 8185);
PAINT MONO (-14200 8185);
DISPLAY INVISIBLE (-14200 8185);
WIRE 16 -1 (-10050 5425)(-11400 5425);
FORCEPROP 0 LAST CDS_PHYS_NET_NAME TP_PCIE_TXP<1>
J 0
(-11310 5459);
PAINT MONO (-11310 5459);
DISPLAY INVISIBLE (-11310 5459);
FORCEPROP 2 LAST SIG_NAME TP_PCIE_TXP[1]
J 0
(-11085 5435);
DISPLAY 0.638298 (-11085 5435);
PAINT WHITE (-11085 5435);
FORCEPROP 2 LASTPROP $XRERR UNIQUE?
J 0
(-10020 5425);
DISPLAY 0.638298 (-10020 5425);
PAINT MONO (-10020 5425);
DISPLAY INVISIBLE (-10020 5425);
WIRE 16 -1 (-10050 5225)(-11400 5225);
FORCEPROP 2 LAST SIG_NAME P2E_MB_BMC_TX_C_DN<0>
J 0
(-11085 5235);
DISPLAY 0.638298 (-11085 5235);
PAINT RED (-11085 5235);
WIRE 16 -1 (-11400 5125)(-9625 5125);
FORCEPROP 2 LAST SIG_NAME TP_PCIE_TXP[3]
J 0
(-11085 5135);
DISPLAY 0.638298 (-11085 5135);
PAINT RED (-11085 5135);
FORCEPROP 2 LASTPROP $XRERR UNIQUE?
J 0
(-11325 5135);
DISPLAY 0.638298 (-11325 5135);
PAINT MONO (-11325 5135);
DISPLAY INVISIBLE (-11325 5135);
WIRE 16 -1 (-11400 5075)(-10025 5075);
FORCEPROP 2 LAST SIG_NAME TP_BEEP_LED
J 0
(-11085 5085);
DISPLAY 0.638298 (-11085 5085);
PAINT RED (-11085 5085);
FORCEPROP 2 LASTPROP $XRERR UNIQUE?
J 0
(-9995 5075);
DISPLAY 0.638298 (-9995 5075);
PAINT MONO (-9995 5075);
DISPLAY INVISIBLE (-9995 5075);
WIRE 16 -1 (-10050 5375)(-11400 5375);
FORCEPROP 0 LAST CDS_PHYS_NET_NAME TP_PCIE_TXN<1>
J 0
(-11310 5409);
PAINT MONO (-11310 5409);
DISPLAY INVISIBLE (-11310 5409);
FORCEPROP 2 LAST SIG_NAME TP_PCIE_TXN[1]
J 0
(-11085 5385);
DISPLAY 0.638298 (-11085 5385);
PAINT WHITE (-11085 5385);
FORCEPROP 2 LASTPROP $XRERR UNIQUE?
J 0
(-10020 5375);
DISPLAY 0.638298 (-10020 5375);
PAINT MONO (-10020 5375);
DISPLAY INVISIBLE (-10020 5375);
WIRE 16 -1 (-10050 5275)(-11400 5275);
FORCEPROP 2 LAST SIG_NAME P2E_MB_BMC_TX_C_DP<0>
J 0
(-11085 5285);
DISPLAY 0.638298 (-11085 5285);
PAINT RED (-11085 5285);
WIRE 16 -1 (-14325 9225)(-12700 9225);
FORCEPROP 0 LAST CDS_PHYS_NET_NAME I3C_SCM_0_SDA
J 0
(-15260 9265);
PAINT MONO (-15260 9265);
DISPLAY INVISIBLE (-15260 9265);
FORCEPROP 2 LAST SIG_NAME I3C_SCM_0_SDA
J 0
(-13885 9235);
DISPLAY 0.638298 (-13885 9235);
PAINT WHITE (-13885 9235);
FORCEPROP 2 LASTPROP $XRERR UNIQUE?
J 0
(-14125 9235);
DISPLAY 0.638298 (-14125 9235);
PAINT MONO (-14125 9235);
DISPLAY INVISIBLE (-14125 9235);
WIRE 16 -1 (-14325 9175)(-12700 9175);
FORCEPROP 2 LAST SIG_NAME I3C_SCM_1_SCL
J 0
(-13885 9185);
DISPLAY 0.638298 (-13885 9185);
PAINT WHITE (-13885 9185);
FORCEPROP 2 LASTPROP $XRERR UNIQUE?
J 0
(-14125 9185);
DISPLAY 0.638298 (-14125 9185);
PAINT MONO (-14125 9185);
DISPLAY INVISIBLE (-14125 9185);
WIRE 16 -1 (-14325 9125)(-12700 9125);
FORCEPROP 2 LAST SIG_NAME I3C_SCM_1_SDA
J 0
(-13885 9135);
DISPLAY 0.638298 (-13885 9135);
PAINT WHITE (-13885 9135);
FORCEPROP 2 LASTPROP $XRERR UNIQUE?
J 0
(-14125 9135);
DISPLAY 0.638298 (-14125 9135);
PAINT MONO (-14125 9135);
DISPLAY INVISIBLE (-14125 9135);
WIRE 16 -1 (-14325 9075)(-12700 9075);
FORCEPROP 2 LAST SIG_NAME I3C_SCM_2_SCL
J 0
(-13885 9085);
DISPLAY 0.638298 (-13885 9085);
PAINT WHITE (-13885 9085);
FORCEPROP 2 LASTPROP $XRERR UNIQUE?
J 0
(-14125 9085);
DISPLAY 0.638298 (-14125 9085);
PAINT MONO (-14125 9085);
DISPLAY INVISIBLE (-14125 9085);
WIRE 16 -1 (-14325 9025)(-12700 9025);
FORCEPROP 2 LAST SIG_NAME I3C_SCM_2_SDA
J 0
(-13885 9035);
DISPLAY 0.638298 (-13885 9035);
PAINT WHITE (-13885 9035);
FORCEPROP 2 LASTPROP $XRERR UNIQUE?
J 0
(-14125 9035);
DISPLAY 0.638298 (-14125 9035);
PAINT MONO (-14125 9035);
DISPLAY INVISIBLE (-14125 9035);
WIRE 16 -1 (-15025 8625)(-16175 8625);
FORCEPROP 0 LAST SIG_NAME SMB_OCP_SFF_3V3AUX_SDA
J 0
(-16060 8635);
DISPLAY 0.553191 (-16060 8635);
PAINT WHITE (-16060 8635);
WIRE 16 -1 (-15025 8575)(-16200 8575);
FORCEPROP 2 LAST SIG_NAME SMB_CPU0_CPU1_APML_SCL
J 0
(-16060 8585);
DISPLAY 0.510638 (-16060 8585);
PAINT WHITE (-16060 8585);
WIRE 16 -1 (-15025 8475)(-16200 8475);
FORCEPROP 0 LAST SIG_NAME SMB_VR_SENSOR_3V3AUX_SCL
J 0
(-16060 8485);
DISPLAY 0.553191 (-16060 8485);
PAINT WHITE (-16060 8485);
WIRE 16 -1 (-15025 8425)(-16175 8425);
FORCEPROP 0 LAST SIG_NAME SMB_VR_SENSOR_3V3AUX_SDA
J 0
(-16060 8435);
DISPLAY 0.553191 (-16060 8435);
PAINT WHITE (-16060 8435);
WIRE 16 -1 (-15025 8375)(-16200 8375);
FORCEPROP 0 LAST SIG_NAME SMB_CPU0_CPU1_SEC_SCL
J 0
(-16060 8385);
DISPLAY 0.553191 (-16060 8385);
PAINT WHITE (-16060 8385);
WIRE 16 -1 (-15025 8325)(-16175 8325);
FORCEPROP 0 LAST SIG_NAME SMB_CPU0_CPU1_SEC_SDA
J 0
(-16060 8335);
DISPLAY 0.553191 (-16060 8335);
PAINT WHITE (-16060 8335);
WIRE 16 -1 (-12700 7175)(-14050 7175);
FORCEPROP 0 LAST SIG_NAME SMB_FAN_3V3AUX_SCL
J 0
(-13960 7185);
DISPLAY 0.680851 (-13960 7185);
PAINT WHITE (-13960 7185);
WIRE 16 -1 (-12700 7325)(-14825 7325);
FORCEPROP 0 LAST SIG_NAME SMB_1_PLD_3V3AUX_SDA_R3
J 0
(-13960 7335);
DISPLAY 0.680851 (-13960 7335);
PAINT WHITE (-13960 7335);
FORCEPROP 2 LASTPROP $XRERR UNIQUE?
J 0
(-14200 7335);
DISPLAY 0.638298 (-14200 7335);
PAINT MONO (-14200 7335);
DISPLAY INVISIBLE (-14200 7335);
WIRE 16 -1 (-12700 7375)(-14825 7375);
FORCEPROP 0 LAST SIG_NAME SMB_1_PLD_3V3AUX_SCL_R3
J 0
(-13960 7385);
DISPLAY 0.680851 (-13960 7385);
PAINT WHITE (-13960 7385);
FORCEPROP 2 LASTPROP $XRERR UNIQUE?
J 0
(-14200 7385);
DISPLAY 0.638298 (-14200 7385);
PAINT MONO (-14200 7385);
DISPLAY INVISIBLE (-14200 7385);
WIRE 16 -1 (-12700 7425)(-14825 7425);
FORCEPROP 2 LAST SIG_NAME SMB_PMBUS_3V3AUX_SDA_R0
J 0
(-13960 7435);
DISPLAY 0.638298 (-13960 7435);
PAINT WHITE (-13960 7435);
FORCEPROP 2 LASTPROP $XRERR UNIQUE?
J 0
(-14200 7435);
DISPLAY 0.638298 (-14200 7435);
PAINT MONO (-14200 7435);
DISPLAY INVISIBLE (-14200 7435);
WIRE 16 -1 (-12700 7475)(-14825 7475);
FORCEPROP 2 LAST SIG_NAME SMB_PMBUS_3V3AUX_SCL_R0
J 0
(-13960 7485);
DISPLAY 0.638298 (-13960 7485);
PAINT WHITE (-13960 7485);
FORCEPROP 2 LASTPROP $XRERR UNIQUE?
J 0
(-14200 7485);
DISPLAY 0.638298 (-14200 7485);
PAINT MONO (-14200 7485);
DISPLAY INVISIBLE (-14200 7485);
WIRE 16 -1 (-15025 7375)(-16175 7375);
FORCEPROP 0 LAST SIG_NAME SMB_1_PLD_3V3AUX_SCL
J 0
(-16060 7385);
DISPLAY 0.553191 (-16060 7385);
PAINT WHITE (-16060 7385);
WIRE 16 -1 (-15025 7425)(-16150 7425);
FORCEPROP 0 LAST SIG_NAME SMB_PMBUS_3V3AUX_SDA
J 0
(-16060 7435);
DISPLAY 0.553191 (-16060 7435);
PAINT WHITE (-16060 7435);
WIRE 16 -1 (-15025 7475)(-16175 7475);
FORCEPROP 0 LAST SIG_NAME SMB_PMBUS_3V3AUX_SCL
J 0
(-16060 7485);
DISPLAY 0.553191 (-16060 7485);
PAINT WHITE (-16060 7485);
WIRE 16 -1 (-15025 8125)(-16175 8125);
FORCEPROP 0 LAST SIG_NAME SMB_OCP_V3_2_3V3AUX_SDA
J 0
(-16060 8135);
DISPLAY 0.553191 (-16060 8135);
PAINT WHITE (-16060 8135);
WIRE 16 -1 (-15025 8525)(-16175 8525);
FORCEPROP 2 LAST SIG_NAME SMB_CPU0_CPU1_APML_SDA
J 0
(-16060 8535);
DISPLAY 0.510638 (-16060 8535);
PAINT WHITE (-16060 8535);
WIRE 16 -1 (-15050 7075)(-16175 7075);
FORCEPROP 0 LAST SIG_NAME SMB_2_BMC_GPU_SCL
J 0
(-16060 7085);
DISPLAY 0.553191 (-16060 7085);
PAINT WHITE (-16060 7085);
WIRE 16 -1 (-12700 8225)(-14050 8225);
FORCEPROP 2 LAST SIG_NAME I3C_BMC_SWB_SDA
J 0
(-13960 8235);
DISPLAY 0.638298 (-13960 8235);
PAINT WHITE (-13960 8235);
WIRE 16 -1 (-12700 8275)(-14050 8275);
FORCEPROP 2 LAST SIG_NAME I3C_BMC_SWB_SCL
J 0
(-13960 8285);
DISPLAY 0.638298 (-13960 8285);
PAINT WHITE (-13960 8285);
WIRE 16 -1 (-12700 8325)(-14825 8325);
FORCEPROP 0 LAST SIG_NAME SMB_CPU0_CPU1_SEC_SDA_R
J 0
(-13960 8335);
DISPLAY 0.680851 (-13960 8335);
PAINT WHITE (-13960 8335);
FORCEPROP 2 LASTPROP $XRERR UNIQUE?
J 0
(-14200 8335);
DISPLAY 0.638298 (-14200 8335);
PAINT MONO (-14200 8335);
DISPLAY INVISIBLE (-14200 8335);
WIRE 16 -1 (-12700 8375)(-14825 8375);
FORCEPROP 0 LAST SIG_NAME SMB_CPU0_CPU1_SEC_SCL_R
J 0
(-13960 8385);
DISPLAY 0.680851 (-13960 8385);
PAINT WHITE (-13960 8385);
FORCEPROP 2 LASTPROP $XRERR UNIQUE?
J 0
(-14200 8385);
DISPLAY 0.638298 (-14200 8385);
PAINT MONO (-14200 8385);
DISPLAY INVISIBLE (-14200 8385);
WIRE 16 -1 (-12700 8425)(-14825 8425);
FORCEPROP 2 LAST SIG_NAME SMB_VR_3V3AUX_SDA_R0
J 0
(-13960 8435);
DISPLAY 0.638298 (-13960 8435);
PAINT WHITE (-13960 8435);
FORCEPROP 2 LASTPROP $XRERR UNIQUE?
J 0
(-14200 8435);
DISPLAY 0.638298 (-14200 8435);
PAINT MONO (-14200 8435);
DISPLAY INVISIBLE (-14200 8435);
WIRE 16 -1 (-15025 8675)(-16200 8675);
FORCEPROP 0 LAST SIG_NAME SMB_OCP_SFF_3V3AUX_SCL
J 0
(-16060 8685);
DISPLAY 0.553191 (-16060 8685);
PAINT WHITE (-16060 8685);
WIRE 16 -1 (-15025 8175)(-16200 8175);
FORCEPROP 0 LAST SIG_NAME SMB_OCP_V3_2_3V3AUX_SCL
J 0
(-16060 8185);
DISPLAY 0.553191 (-16060 8185);
PAINT WHITE (-16060 8185);
WIRE 16 -1 (-15050 7025)(-16150 7025);
FORCEPROP 0 LAST SIG_NAME SMB_2_BMC_GPU_SDA
J 0
(-16060 7035);
DISPLAY 0.553191 (-16060 7035);
PAINT WHITE (-16060 7035);
WIRE 16 -1 (-15025 7325)(-16150 7325);
FORCEPROP 0 LAST SIG_NAME SMB_1_PLD_3V3AUX_SDA
J 0
(-16060 7335);
DISPLAY 0.553191 (-16060 7335);
PAINT WHITE (-16060 7335);
WIRE 16 -1 (-14525 8925)(-15575 8925);
FORCEPROP 2 LAST SIG_NAME I3C_SCM_3_R_SDA
J 0
(-15460 8935);
DISPLAY 0.638298 (-15460 8935);
PAINT WHITE (-15460 8935);
WIRE 16 -1 (-15575 9025)(-14525 9025);
FORCEPROP 2 LAST SIG_NAME I3C_SCM_2_R_SDA
J 0
(-15460 9035);
DISPLAY 0.638298 (-15460 9035);
PAINT WHITE (-15460 9035);
WIRE 16 -1 (-15575 9075)(-14525 9075);
FORCEPROP 2 LAST SIG_NAME I3C_SCM_2_R_SCL
J 0
(-15460 9085);
DISPLAY 0.638298 (-15460 9085);
PAINT WHITE (-15460 9085);
WIRE 16 -1 (-15575 9125)(-14525 9125);
FORCEPROP 2 LAST SIG_NAME I3C_SCM_1_R_SDA
J 0
(-15460 9135);
DISPLAY 0.638298 (-15460 9135);
PAINT WHITE (-15460 9135);
WIRE 16 -1 (-15575 9175)(-14525 9175);
FORCEPROP 2 LAST SIG_NAME I3C_SCM_1_R_SCL
J 0
(-15460 9185);
DISPLAY 0.638298 (-15460 9185);
PAINT WHITE (-15460 9185);
WIRE 16 -1 (-14050 7875)(-12700 7875);
FORCEPROP 2 LAST SIG_NAME P2E_CPU0_P5_TX_C_DP
J 0
(-13960 7885);
DISPLAY 0.638298 (-13960 7885);
PAINT WHITE (-13960 7885);
WIRE 16 -1 (-14050 7975)(-12700 7975);
FORCEPROP 2 LAST SIG_NAME CLK_100M_CPU0_CLK01_DN
J 0
(-13960 7985);
DISPLAY 0.638298 (-13960 7985);
PAINT WHITE (-13960 7985);
WIRE 16 -1 (-12700 8475)(-14825 8475);
FORCEPROP 2 LAST SIG_NAME SMB_VR_3V3AUX_SCL_R0
J 0
(-13960 8485);
DISPLAY 0.638298 (-13960 8485);
PAINT WHITE (-13960 8485);
FORCEPROP 2 LASTPROP $XRERR UNIQUE?
J 0
(-14200 8485);
DISPLAY 0.638298 (-14200 8485);
PAINT MONO (-14200 8485);
DISPLAY INVISIBLE (-14200 8485);
WIRE 16 -1 (-12700 8525)(-14825 8525);
FORCEPROP 2 LAST SIG_NAME SMB_CPU0_CPU1_APML_SDA_R
J 0
(-13960 8535);
DISPLAY 0.638298 (-13960 8535);
PAINT WHITE (-13960 8535);
FORCEPROP 2 LASTPROP $XRERR UNIQUE?
J 0
(-14200 8535);
DISPLAY 0.638298 (-14200 8535);
PAINT MONO (-14200 8535);
DISPLAY INVISIBLE (-14200 8535);
WIRE 16 -1 (-12700 8575)(-14825 8575);
FORCEPROP 2 LAST SIG_NAME SMB_CPU0_CPU1_APML_SCL_R
J 0
(-13960 8585);
DISPLAY 0.638298 (-13960 8585);
PAINT WHITE (-13960 8585);
FORCEPROP 2 LASTPROP $XRERR UNIQUE?
J 0
(-14200 8585);
DISPLAY 0.638298 (-14200 8585);
PAINT MONO (-14200 8585);
DISPLAY INVISIBLE (-14200 8585);
WIRE 16 -1 (-12700 8675)(-14825 8675);
FORCEPROP 2 LAST SIG_NAME SMB_OCP_SFF_3V3AUX_SCL_R0
J 0
(-13960 8685);
DISPLAY 0.638298 (-13960 8685);
PAINT WHITE (-13960 8685);
FORCEPROP 2 LASTPROP $XRERR UNIQUE?
J 0
(-14200 8685);
DISPLAY 0.638298 (-14200 8685);
PAINT MONO (-14200 8685);
DISPLAY INVISIBLE (-14200 8685);
WIRE 16 -1 (-12700 8825)(-14050 8825);
FORCEPROP 2 LAST SIG_NAME VIRTUAL_RESEAT
J 0
(-13960 8835);
DISPLAY 0.638298 (-13960 8835);
PAINT WHITE (-13960 8835);
WIRE 16 -1 (-12700 8925)(-14325 8925);
FORCEPROP 2 LAST SIG_NAME I3C_SCM_3_SDA
J 0
(-13885 8935);
DISPLAY 0.638298 (-13885 8935);
PAINT WHITE (-13885 8935);
FORCEPROP 2 LASTPROP $XRERR UNIQUE?
J 0
(-14125 8935);
DISPLAY 0.638298 (-14125 8935);
PAINT MONO (-14125 8935);
DISPLAY INVISIBLE (-14125 8935);
WIRE 16 -1 (-12700 8975)(-14325 8975);
FORCEPROP 2 LAST SIG_NAME I3C_SCM_3_SCL
J 0
(-13885 8985);
DISPLAY 0.638298 (-13885 8985);
PAINT WHITE (-13885 8985);
FORCEPROP 2 LASTPROP $XRERR UNIQUE?
J 0
(-14125 8985);
DISPLAY 0.638298 (-14125 8985);
PAINT MONO (-14125 8985);
DISPLAY INVISIBLE (-14125 8985);
WIRE 16 -1 (-12700 8625)(-14825 8625);
FORCEPROP 2 LAST SIG_NAME SMB_OCP_SFF_3V3AUX_SDA_R0
J 0
(-13960 8635);
DISPLAY 0.638298 (-13960 8635);
PAINT WHITE (-13960 8635);
FORCEPROP 2 LASTPROP $XRERR UNIQUE?
J 0
(-14200 8635);
DISPLAY 0.638298 (-14200 8635);
PAINT MONO (-14200 8635);
DISPLAY INVISIBLE (-14200 8635);
WIRE 16 -1 (-14325 9275)(-12700 9275);
FORCEPROP 0 LAST CDS_PHYS_NET_NAME I3C_SCM_0_SCL
J 0
(-15260 9315);
PAINT MONO (-15260 9315);
DISPLAY INVISIBLE (-15260 9315);
FORCEPROP 2 LAST SIG_NAME I3C_SCM_0_SCL
J 0
(-13885 9285);
DISPLAY 0.638298 (-13885 9285);
PAINT WHITE (-13885 9285);
FORCEPROP 2 LASTPROP $XRERR UNIQUE?
J 0
(-14125 9285);
DISPLAY 0.638298 (-14125 9285);
PAINT MONO (-14125 9285);
DISPLAY INVISIBLE (-14125 9285);
WIRE 16 -1 (-10200 7125)(-9425 7125);
FORCEPROP 2 LAST SIG_NAME SGPIO_SCM_CLK_<0>
J 0
(-10010 7135);
DISPLAY 0.638298 (-10010 7135);
PAINT WHITE (-10010 7135);
WIRE 16 -1 (-12700 6725)(-14850 6725);
FORCEPROP 0 LAST SIG_NAME SMB_PCIE3_3V3AUX_SCL_R
J 0
(-13960 6735);
DISPLAY 0.680851 (-13960 6735);
PAINT WHITE (-13960 6735);
FORCEPROP 2 LASTPROP $XRERR UNIQUE?
J 0
(-14200 6735);
DISPLAY 0.638298 (-14200 6735);
PAINT MONO (-14200 6735);
DISPLAY INVISIBLE (-14200 6735);
WIRE 16 -1 (-14050 7525)(-12700 7525);
FORCEPROP 2 LAST SIG_NAME SMB_PCIE0_3V3AUX_SDA
J 0
(-13960 7535);
DISPLAY 0.638298 (-13960 7535);
PAINT WHITE (-13960 7535);
WIRE 16 -1 (-14050 7575)(-12700 7575);
FORCEPROP 2 LAST SIG_NAME SMB_PCIE0_3V3AUX_SCL
J 0
(-13960 7585);
DISPLAY 0.638298 (-13960 7585);
PAINT WHITE (-13960 7585);
WIRE 16 -1 (-12700 7725)(-14050 7725);
FORCEPROP 2 LAST SIG_NAME P2E_CPU0_P5_RX_DP
J 0
(-13960 7735);
DISPLAY 0.638298 (-13960 7735);
PAINT WHITE (-13960 7735);
WIRE 16 -1 (-14050 7825)(-12700 7825);
FORCEPROP 2 LAST SIG_NAME P2E_CPU0_P5_TX_C_DN
J 0
(-13960 7835);
DISPLAY 0.638298 (-13960 7835);
PAINT WHITE (-13960 7835);
WIRE 16 -1 (-14050 8025)(-12700 8025);
FORCEPROP 2 LAST SIG_NAME CLK_100M_CPU0_CLK01_DP
J 0
(-13960 8035);
DISPLAY 0.638298 (-13960 8035);
PAINT WHITE (-13960 8035);
WIRE 16 -1 (-9725 9075)(-8375 9075);
FORCEPROP 2 LAST SIG_NAME UART_CPU0_SCM_LVC3_UART1_TX
J 0
(-9285 9085);
DISPLAY 0.638298 (-9285 9085);
PAINT WHITE (-9285 9085);
WIRE 16 -1 (-9425 5125)(-8450 5125);
FORCEPROP 2 LAST SIG_NAME LED_HDD_ACTIVITY_B_N
J 0
(-9060 5135);
DISPLAY 0.638298 (-9060 5135);
PAINT WHITE (-9060 5135);
WIRE 16 -1 (-12700 6775)(-14050 6775);
FORCEPROP 2 LAST SIG_NAME JTAG_SCM_TDO_R
J 0
(-13960 6785);
DISPLAY 0.638298 (-13960 6785);
PAINT WHITE (-13960 6785);
WIRE 16 -1 (-8425 8825)(-9350 8825);
FORCEPROP 2 LAST SIG_NAME FM_SOL_UART_CH_SEL
J 0
(-9035 8835);
DISPLAY 0.638298 (-9035 8835);
PAINT RED (-9035 8835);
WIRE 16 -1 (-8375 9125)(-9725 9125);
FORCEPROP 2 LAST SIG_NAME UART_CPU0_SCM_LVC3_UART1_R_RX
J 0
(-9285 9135);
DISPLAY 0.638298 (-9285 9135);
PAINT WHITE (-9285 9135);
WIRE 16 -1 (-12700 6825)(-14050 6825);
FORCEPROP 2 LAST SIG_NAME JTAG_SCM_TDI_R
J 0
(-13960 6835);
DISPLAY 0.638298 (-13960 6835);
PAINT WHITE (-13960 6835);
WIRE 16 -1 (-12700 6875)(-14050 6875);
FORCEPROP 2 LAST SIG_NAME JTAG_SCM_TMS
J 0
(-13960 6885);
DISPLAY 0.638298 (-13960 6885);
PAINT WHITE (-13960 6885);
WIRE 16 -1 (-12700 6925)(-14050 6925);
FORCEPROP 2 LAST SIG_NAME JTAG_SCM_TCK
J 0
(-13960 6935);
DISPLAY 0.638298 (-13960 6935);
PAINT WHITE (-13960 6935);
WIRE 16 -1 (-12700 7125)(-14050 7125);
FORCEPROP 0 LAST SIG_NAME SMB_FAN_3V3AUX_SDA
J 0
(-13960 7135);
DISPLAY 0.680851 (-13960 7135);
PAINT WHITE (-13960 7135);
WIRE 16 -1 (-10050 7775)(-11400 7775);
FORCEPROP 0 LAST CDS_PHYS_NET_NAME RMII_OCP_BMC_CRSDV
J 0
(-11310 7815);
PAINT MONO (-11310 7815);
DISPLAY INVISIBLE (-11310 7815);
FORCEPROP 2 LAST SIG_NAME RMII_OCP_BMC_CRSDV
J 0
(-11085 7785);
DISPLAY 0.638298 (-11085 7785);
PAINT WHITE (-11085 7785);
WIRE 16 -1 (-10050 7675)(-11400 7675);
FORCEPROP 2 LAST SIG_NAME RMII_BMC_OCP_TXD_0
J 0
(-11085 7685);
DISPLAY 0.638298 (-11085 7685);
PAINT WHITE (-11085 7685);
WIRE 16 -1 (-10050 7575)(-11400 7575);
FORCEPROP 0 LAST CDS_PHYS_NET_NAME RMII_BMC_OCP_RX_ER
J 0
(-11310 7615);
PAINT MONO (-11310 7615);
DISPLAY INVISIBLE (-11310 7615);
FORCEPROP 2 LAST SIG_NAME RMII_BMC_OCP_RX_ER
J 0
(-11085 7585);
DISPLAY 0.638298 (-11085 7585);
PAINT WHITE (-11085 7585);
WIRE 16 -1 (-10050 7825)(-11400 7825);
FORCEPROP 0 LAST CDS_PHYS_NET_NAME CLK_50M_RMII_BMC_OCP
J 0
(-11310 7865);
PAINT MONO (-11310 7865);
DISPLAY INVISIBLE (-11310 7865);
FORCEPROP 2 LAST SIG_NAME CLK_50M_RMII_BMC_OCP
J 0
(-11085 7835);
DISPLAY 0.638298 (-11085 7835);
PAINT WHITE (-11085 7835);
WIRE 16 -1 (-10050 8925)(-11400 8925);
FORCEPROP 0 LAST CDS_PHYS_NET_NAME SPI_CPU0_LVC3_TPM_CS_N
J 0
(-11310 8959);
PAINT MONO (-11310 8959);
DISPLAY INVISIBLE (-11310 8959);
FORCEPROP 2 LAST SIG_NAME SPI_CPU0_LVC3_TPM_CS_N
J 0
(-11085 8935);
DISPLAY 0.638298 (-11085 8935);
PAINT RED (-11085 8935);
WIRE 16 -1 (-9875 9375)(-9875 9725);
WIRE 16 -1 (-9875 9375)(-11400 9375);
FORCEPROP 2 LAST SIG_NAME PRSNT0_N
J 0
(-11085 9385);
DISPLAY 0.638298 (-11085 9385);
PAINT WHITE (-11085 9385);
FORCEPROP 2 LASTPROP $XRERR UNIQUE?
J 0
(-11325 9385);
DISPLAY 0.638298 (-11325 9385);
PAINT MONO (-11325 9385);
DISPLAY INVISIBLE (-11325 9385);
WIRE 16 -1 (-9875 9725)(-9275 9725);
WIRE 16 -1 (-9275 9650)(-9275 9725);
WIRE 16 -1 (-10050 9275)(-11400 9275);
FORCEPROP 0 LAST CDS_PHYS_NET_NAME UART_BMC_BIC_TX
J 0
(-11310 9309);
PAINT MONO (-11310 9309);
DISPLAY INVISIBLE (-11310 9309);
FORCEPROP 2 LAST SIG_NAME UART_BMC_BIC_TX
J 0
(-11085 9285);
DISPLAY 0.638298 (-11085 9285);
PAINT WHITE (-11085 9285);
WIRE 16 -1 (-10050 9225)(-11400 9225);
FORCEPROP 0 LAST CDS_PHYS_NET_NAME UART_BMC_BIC_BUF_RX
J 0
(-11310 9259);
PAINT MONO (-11310 9259);
DISPLAY INVISIBLE (-11310 9259);
FORCEPROP 2 LAST SIG_NAME UART_BMC_BIC_BUF_RX
J 0
(-11085 9235);
DISPLAY 0.638298 (-11085 9235);
PAINT WHITE (-11085 9235);
WIRE 16 -1 (-11400 9125)(-9925 9125);
FORCEPROP 0 LAST CDS_PHYS_NET_NAME TP_UART_CPU0_SCM_LVC3_UART1_RX
J 0
(-11310 9159);
PAINT MONO (-11310 9159);
DISPLAY INVISIBLE (-11310 9159);
FORCEPROP 2 LAST SIG_NAME UART_CPU0_SCM_LVC3_UART1_RX
J 0
(-11085 9135);
DISPLAY 0.638298 (-11085 9135);
PAINT WHITE (-11085 9135);
FORCEPROP 2 LASTPROP $XRERR UNIQUE?
J 0
(-11325 9135);
DISPLAY 0.638298 (-11325 9135);
PAINT MONO (-11325 9135);
DISPLAY INVISIBLE (-11325 9135);
WIRE 16 -1 (-11400 9075)(-9925 9075);
FORCEPROP 0 LAST CDS_PHYS_NET_NAME TP_UART_CPU0_SCM_LVC3_UART1_TX
J 0
(-11310 9109);
PAINT MONO (-11310 9109);
DISPLAY INVISIBLE (-11310 9109);
FORCEPROP 2 LAST SIG_NAME UART_CPU0_SCM_LVC3_UART1_R1_TX
J 0
(-11085 9085);
DISPLAY 0.638298 (-11085 9085);
PAINT WHITE (-11085 9085);
FORCEPROP 2 LASTPROP $XRERR UNIQUE?
J 0
(-11325 9085);
DISPLAY 0.638298 (-11325 9085);
PAINT MONO (-11325 9085);
DISPLAY INVISIBLE (-11325 9085);
WIRE 16 -1 (-10050 8975)(-11400 8975);
FORCEPROP 0 LAST CDS_PHYS_NET_NAME TP_SPI_TPM_CLK
J 0
(-11310 9009);
PAINT MONO (-11310 9009);
DISPLAY INVISIBLE (-11310 9009);
FORCEPROP 2 LAST SIG_NAME RST_SRST_PLD_BMC_N
J 0
(-11085 8985);
DISPLAY 0.638298 (-11085 8985);
PAINT RED (-11085 8985);
WIRE 16 -1 (-10200 6525)(-9375 6525);
FORCEPROP 2 LAST SIG_NAME FM_AC_PWR_BTN_R_N
J 0
(-10035 6535);
DISPLAY 0.680851 (-10035 6535);
WIRE 16 -1 (-10200 6775)(-9425 6775);
FORCEPROP 2 LAST SIG_NAME SGPIO_SCM_LD_<1>
J 0
(-10010 6785);
DISPLAY 0.638298 (-10010 6785);
PAINT WHITE (-10010 6785);
WIRE 16 -1 (-10200 7175)(-9425 7175);
FORCEPROP 2 LAST SIG_NAME SGPIO_SCM_DO_<0>
J 0
(-10010 7185);
DISPLAY 0.638298 (-10010 7185);
PAINT WHITE (-10010 7185);
WIRE 16 -1 (-9425 6925)(-10200 6925);
FORCEPROP 2 LAST SIG_NAME SGPIO_SCM_DO_<1>
J 0
(-10010 6935);
DISPLAY 0.638298 (-10010 6935);
PAINT WHITE (-10010 6935);
WIRE 16 -1 (-9425 6875)(-10200 6875);
FORCEPROP 2 LAST SIG_NAME SGPIO_SCM_CLK_<1>
J 0
(-10010 6885);
DISPLAY 0.638298 (-10010 6885);
PAINT WHITE (-10010 6885);
WIRE 16 -1 (-10200 6825)(-9425 6825);
FORCEPROP 2 LAST SIG_NAME SGPIO_SCM_DI_<1>
J 0
(-10010 6835);
DISPLAY 0.638298 (-10010 6835);
PAINT WHITE (-10010 6835);
DOT 1 (-8700 6825);
DOT 1 (-11200 9175);
DOT 1 (-11200 5475);
CIRCLE (-9500 9175)(-9410 9175);
PAINT YELLOW (-9500 9175);
DOT 1 (-11200 9025);
DOT 1 (-15200 4475);
DOT 1 (-11200 5025);
DOT 1 (-11200 5175);
DOT 1 (-11200 5325);
DOT 1 (-11200 5625);
DOT 1 (-11200 5925);
DOT 1 (-11200 5775);
DOT 1 (-11200 6075);
DOT 1 (-11200 6725);
DOT 1 (-11200 6975);
DOT 1 (-11200 7425);
DOT 1 (-11200 7875);
DOT 1 (-11200 9475);
DOT 1 (-12925 4825);
DOT 1 (-12925 4875);
DOT 1 (-12925 5025);
DOT 1 (-12925 4925);
DOT 1 (-12925 5325);
DOT 1 (-12925 5175);
DOT 1 (-12925 6975);
DOT 1 (-12925 7625);
DOT 1 (-12925 7775);
DOT 1 (-12925 7925);
DOT 1 (-12925 8075);
DOT 1 (-12925 8875);
DOT 1 (-12925 9325);
DOT 1 (-12925 9475);
DOT 1 (-12925 4725);
DOT 1 (-12925 4775);
DOT 1 (-12925 6525);
DOT 1 (-11200 8225);
DOT 1 (-12925 5625);
DOT 1 (-12925 5475);
FORCENOTE
SPI FROM MB TO SCM_BIOS FLASH
(-9650 8025) 0;
DISPLAY LEFT (-9650 8025);
DISPLAY 0.638298 (-9650 8025);
PAINT SKYBLUE (-9650 8025);
FORCENOTE
TBC
(-8775 8400) 0;
DISPLAY LEFT (-8775 8400);
DISPLAY 1.021277 (-8775 8400);
FORCENOTE
RERSERVE
(-9675 9225) 0;
DISPLAY LEFT (-9675 9225);
DISPLAY 1.021277 (-9675 9225);
FORCENOTE
SPI FROM SCM TO MB FPGA
(-9975 6250) 0;
DISPLAY LEFT (-9975 6250);
DISPLAY 0.638298 (-9975 6250);
PAINT SKYBLUE (-9975 6250);
QUIT
